# Altium SchDoc records: 01-USER_IO.SchDoc
|HEADER=Protel for Windows - Schematic Capture Binary File Version 5.0|Weight=1632|MinorVersion=6
|RECORD=31|FontIdCount=7|Size1=10|FontName1=Times New Roman|Size2=8|FontName2=Arial|Size3=10|FontName3=Arial|Size4=12|Underline4=T|FontName4=Arial|Size5=11|FontName5=Arial|Size6=24|FontName6=Times New Roman|Size7=10|Underline7=T|FontName7=Times New Roman|UseMBCS=T|IsBOC=T|HotSpotGridOn=T|HotSpotGridSize=5|SheetStyle=12|SystemFont=3|BorderOn=T|SheetNumberSpaceSize=12|AreaColor=16317695|SnapGridOn=T|SnapGridSize=10|VisibleGridOn=T|VisibleGridSize=10|CustomX=2338|CustomX_Frac=58268|CustomY=1653|CustomY_Frac=54331|CustomXZones=8|CustomYZones=6|CustomMarginWidth=19|CustomMarginWidth_Frac=80000|ShowTemplateGraphics=T|TemplateFileName=C:\Users\<user>\Documents\Altium\AD20\Templates\Timecard.SchDot|Display_Unit=0
|RECORD=39|IsNotAccesible=T|OwnerPartId=-1|FileName=C:\Users\<user>\Documents\Altium\AD20\Templates\Timecard.SchDot
|RECORD=4|OwnerIndex=1|OwnerPartId=-1|Location.X=1594|Location.Y=39|Color=8388608|FontID=4|Text=timingcard.com|URL=http://timingcard.com
|RECORD=6|OwnerIndex=1|IndexInSheet=1|OwnerPartId=-1|LocationCount=2|X1=1680|Y1=35|X2=1576|Y2=35
|RECORD=4|OwnerIndex=1|IndexInSheet=2|OwnerPartId=-1|Location.X=1615|Location.Y=27|Justification=4|Color=16711680|FontID=5|Text==SheetNumber
|RECORD=4|OwnerIndex=1|IndexInSheet=3|OwnerPartId=-1|Location.X=1581|Location.X_Frac=42446|Location.Y=29|Location.Y_Frac=96838|Justification=3|FontID=2|Text=SHEET
|RECORD=4|OwnerIndex=1|IndexInSheet=4|OwnerPartId=-1|Location.X=1639|Location.X_Frac=42446|Location.Y=29|Location.Y_Frac=96838|Justification=3|FontID=2|Text=OF
|RECORD=6|OwnerIndex=1|IndexInSheet=5|OwnerPartId=-1|LineWidth=1|LocationCount=2|X1=1679|X1_Frac=42446|Y1=117|Y1_Frac=96838|X2=1576|Y2=118
|RECORD=4|OwnerIndex=1|IndexInSheet=6|OwnerPartId=-1|Location.X=1659|Location.Y=27|Justification=4|Color=16711680|FontID=5|Text==SheetTotal
|RECORD=30|OwnerIndex=1|IndexInSheet=7|OwnerPartId=-1|Location.X=1578|Location.Y=65|Corner.X=1673|Corner.X_Frac=88801|Corner.Y=115|KeepAspect=T|FileName=C:\Users\<user>\Desktop\Timecard Logo\TIMECARD.jpg
|RECORD=6|OwnerIndex=1|IndexInSheet=8|OwnerPartId=-1|LineWidth=1|LocationCount=2|X1=1576|X1_Frac=3162|Y1=117|Y1_Frac=42446|X2=1576|Y2=21
|RECORD=6|OwnerIndex=1|IndexInSheet=9|OwnerPartId=-1|LocationCount=2|X1=1680|Y1=51|X2=1576|Y2=51
|RECORD=4|OwnerIndex=1|IndexInSheet=10|OwnerPartId=-1|Location.X=1581|Location.X_Frac=42446|Location.Y=56|Location.Y_Frac=96838|Justification=3|FontID=2|Text=REV
|RECORD=4|OwnerIndex=1|IndexInSheet=11|OwnerPartId=-1|Location.X=1619|Location.Y=57|Justification=3|FontID=2|Text=DATE
|RECORD=6|OwnerIndex=1|IndexInSheet=12|OwnerPartId=-1|LocationCount=2|X1=1680|Y1=65|X2=1576|Y2=65
|RECORD=4|OwnerIndex=1|IndexInSheet=13|OwnerPartId=-1|Location.X=1605|Location.Y=58|Justification=4|Color=16711680|FontID=5|Text==ProjectRevision
|RECORD=4|OwnerIndex=1|IndexInSheet=14|OwnerPartId=-1|Location.X=1659|Location.Y=58|Justification=4|Color=16711680|FontID=5|Text==ProjectDate
|RECORD=41|IndexInSheet=1|OwnerPartId=-1|Color=8388608|FontID=1|IsHidden=T|Text=*|Name=CurrentTime|ReadOnlyState=1
|RECORD=41|IndexInSheet=2|OwnerPartId=-1|Color=8388608|FontID=1|IsHidden=T|Text=*|Name=CurrentDate|ReadOnlyState=1
|RECORD=41|IndexInSheet=3|OwnerPartId=-1|Color=8388608|FontID=1|IsHidden=T|Text=*|Name=Time|ReadOnlyState=1
|RECORD=41|IndexInSheet=4|OwnerPartId=-1|Color=8388608|FontID=1|IsHidden=T|Text=*|Name=Date|ReadOnlyState=1
|RECORD=41|IndexInSheet=5|OwnerPartId=-1|Color=8388608|FontID=1|IsHidden=T|Text=*|Name=DocumentFullPathAndName|ReadOnlyState=1
|RECORD=41|IndexInSheet=6|OwnerPartId=-1|Color=8388608|FontID=1|IsHidden=T|Text=*|Name=DocumentName|ReadOnlyState=1
|RECORD=41|IndexInSheet=7|OwnerPartId=-1|Color=8388608|FontID=1|IsHidden=T|Text=*|Name=ModifiedDate|ReadOnlyState=1
|RECORD=41|IndexInSheet=8|OwnerPartId=-1|Color=8388608|FontID=1|IsHidden=T|Text=*|Name=ApprovedBy|ReadOnlyState=1
|RECORD=41|IndexInSheet=9|OwnerPartId=-1|Color=8388608|FontID=1|IsHidden=T|Text=*|Name=CheckedBy|ReadOnlyState=1
|RECORD=41|IndexInSheet=10|OwnerPartId=-1|Color=8388608|FontID=1|IsHidden=T|Text=*|Name=Author|ReadOnlyState=1
|RECORD=41|IndexInSheet=11|OwnerPartId=-1|Color=8388608|FontID=1|IsHidden=T|Text=*|Name=CompanyName|ReadOnlyState=1
|RECORD=41|IndexInSheet=12|OwnerPartId=-1|Color=8388608|FontID=1|IsHidden=T|Text=*|Name=DrawnBy|ReadOnlyState=1
|RECORD=41|IndexInSheet=13|OwnerPartId=-1|Color=8388608|FontID=1|IsHidden=T|Text=*|Name=Engineer|ReadOnlyState=1
|RECORD=41|IndexInSheet=14|OwnerPartId=-1|Color=8388608|FontID=1|IsHidden=T|Text=*|Name=Organization|ReadOnlyState=1
|RECORD=41|IndexInSheet=15|OwnerPartId=-1|Color=8388608|FontID=1|IsHidden=T|Text=*|Name=Address1|ReadOnlyState=1
|RECORD=41|IndexInSheet=16|OwnerPartId=-1|Color=8388608|FontID=1|IsHidden=T|Text=*|Name=Address2|ReadOnlyState=1
|RECORD=41|IndexInSheet=17|OwnerPartId=-1|Color=8388608|FontID=1|IsHidden=T|Text=*|Name=Address3|ReadOnlyState=1
|RECORD=41|IndexInSheet=18|OwnerPartId=-1|Color=8388608|FontID=1|IsHidden=T|Text=*|Name=Address4|ReadOnlyState=1
|RECORD=41|IndexInSheet=19|OwnerPartId=-1|Color=8388608|FontID=1|IsHidden=T|Text=*|Name=Title|ReadOnlyState=1
|RECORD=41|IndexInSheet=20|OwnerPartId=-1|Color=8388608|FontID=1|IsHidden=T|Text=1|Name=DocumentNumber|ReadOnlyState=1
|RECORD=41|IndexInSheet=21|OwnerPartId=-1|Color=8388608|FontID=1|IsHidden=T|Text=*|Name=Revision|ReadOnlyState=1
|RECORD=41|IndexInSheet=22|OwnerPartId=-1|Color=8388608|FontID=1|IsHidden=T|Text=1|Name=SheetNumber|ReadOnlyState=1
|RECORD=41|IndexInSheet=23|OwnerPartId=-1|Color=8388608|FontID=1|IsHidden=T|Text=7|Name=SheetTotal|ReadOnlyState=1
|RECORD=41|IndexInSheet=24|OwnerPartId=-1|Color=8388608|FontID=1|IsHidden=T|Text=*|Name=Rule|ReadOnlyState=1
|RECORD=41|IndexInSheet=25|OwnerPartId=-1|Color=8388608|FontID=1|IsHidden=T|Text=*|Name=ImagePath|ReadOnlyState=1
|RECORD=41|IndexInSheet=26|OwnerPartId=-1|Color=8388608|FontID=1|IsHidden=T|Text=*|Name=ProjectName|ReadOnlyState=1
|RECORD=41|IndexInSheet=27|OwnerPartId=-1|Color=8388608|FontID=1|IsHidden=T|Text=*|Name=Application_BuildNumber|ReadOnlyState=1
|RECORD=41|IndexInSheet=28|OwnerPartId=-1|Color=8388608|FontID=1|IsHidden=T|Name=ConfigurationParameters|ReadOnlyState=1
|RECORD=41|IndexInSheet=29|OwnerPartId=-1|Color=8388608|FontID=1|IsHidden=T|Name=ConfiguratorName|ReadOnlyState=1
|RECORD=41|IndexInSheet=30|OwnerPartId=-1|Color=8388608|FontID=1|IsHidden=T|Name=VersionControl_RevNumber|ReadOnlyState=1
|RECORD=41|IndexInSheet=31|OwnerPartId=-1|Color=8388608|FontID=1|IsHidden=T|Name=IsUserConfigurable|ReadOnlyState=1
|RECORD=41|IndexInSheet=32|OwnerPartId=-1|Color=8388608|FontID=1|IsHidden=T|Name=VersionControl_ProjFolderRevNumber|ReadOnlyState=1
|RECORD=41|IndexInSheet=33|OwnerPartId=-1|Color=8388608|FontID=1|IsHidden=T|Name=SPICEModelCache|ReadOnlyState=1
|RECORD=1|LibReference=NC7WV125K8X|ComponentDescription=Integrated Circuit|PartCount=2|DisplayModeCount=1|IndexInSheet=34|OwnerPartId=-1|Location.X=394|Location.Y=882|CurrentPartId=1|LibraryPath=*|SourceLibraryName=SamacSys.SchLib|TargetFileName=*|AreaColor=11599871|Color=128|PartIDLocked=T|DesignItemId=NC7WV125K8X|AllPinCount=8
|RECORD=41|OwnerIndex=50|OwnerPartId=-1|Location.X=394|Location.Y=882|Color=8388608|FontID=7|IsHidden=T|Text=https://www.mouser.com/datasheet/2/308/NC7WV125-1301459.pdf|Name=Datasheet Link
|RECORD=41|OwnerIndex=50|IndexInSheet=1|OwnerPartId=-1|Location.X=394|Location.Y=882|Color=8388608|FontID=1|IsHidden=T|Text=0.9mm|Name=Height
|RECORD=41|OwnerIndex=50|IndexInSheet=2|OwnerPartId=-1|Location.X=394|Location.Y=882|Color=8388608|FontID=1|IsHidden=T|Text=ON Semiconductor|Name=Manufacturer_Name
|RECORD=41|OwnerIndex=50|IndexInSheet=3|OwnerPartId=-1|Location.X=394|Location.Y=882|Color=8388608|FontID=1|IsHidden=T|Text=NC7WV125K8X|Name=Manufacturer_Part_Number
|RECORD=41|OwnerIndex=50|IndexInSheet=4|OwnerPartId=-1|Location.X=394|Location.Y=882|Color=8388608|FontID=1|IsHidden=T|Text=512-NC7WV125K8X|Name=Mouser Part Number
|RECORD=41|OwnerIndex=50|IndexInSheet=5|OwnerPartId=-1|Location.X=394|Location.Y=882|Color=8388608|FontID=7|IsHidden=T|Text=https://www.mouser.com/Search/Refine.aspx?Keyword=512-NC7WV125K8X|Name=Mouser Price/Stock
|RECORD=41|OwnerIndex=50|IndexInSheet=6|OwnerPartId=-1|Location.X=394|Location.Y=882|Color=8388608|FontID=1|IsHidden=T|Text=NC7WV125K8X|Name=Arrow Part Number
|RECORD=41|OwnerIndex=50|IndexInSheet=7|OwnerPartId=-1|Location.X=394|Location.Y=882|Color=8388608|FontID=7|IsHidden=T|Text=https://www.arrow.com/en/products/nc7wv125k8x/on-semiconductor|Name=Arrow Price/Stock
|RECORD=14|OwnerIndex=50|IsNotAccesible=T|IndexInSheet=8|OwnerPartId=1|Location.X=414|Location.Y=857|Corner.X=484|Corner.Y=982|LineWidth=1|Color=128|AreaColor=11599871|IsSolid=T
|RECORD=2|OwnerIndex=50|OwnerPartId=1|FormalType=1|Electrical=4|PinConglomerate=58|PinLength=20|Location.X=414|Location.Y=972|Designator=1|SwapIDPart=Ž&Ž||PinPropagationDelay=0.000000E+000
|RECORD=2|OwnerIndex=50|OwnerPartId=1|FormalType=1|Electrical=4|PinConglomerate=58|PinLength=20|Location.X=414|Location.Y=947|Designator=2|SwapIDPart=Ž&Ž||PinPropagationDelay=0.000000E+000
|RECORD=2|OwnerIndex=50|OwnerPartId=1|FormalType=1|Electrical=4|PinConglomerate=58|PinLength=20|Location.X=414|Location.Y=892|Designator=3|SwapIDPart=Ž&Ž||PinPropagationDelay=0.000000E+000
|RECORD=2|OwnerIndex=50|OwnerPartId=1|FormalType=1|Electrical=4|PinConglomerate=58|PinLength=20|Location.X=414|Location.Y=862|Name=GND|Designator=4|SwapIDPart=Ž&Ž||PinPropagationDelay=0.000000E+000
|RECORD=2|OwnerIndex=50|OwnerPartId=1|FormalType=1|Electrical=4|PinConglomerate=58|PinLength=20|Location.X=414|Location.Y=872|Name=VCC|Designator=8|SwapIDPart=Ž&Ž||PinPropagationDelay=0.000000E+000
|RECORD=2|OwnerIndex=50|OwnerPartId=1|FormalType=1|Electrical=4|PinConglomerate=58|PinLength=20|Location.X=414|Location.Y=917|Designator=7|SwapIDPart=Ž&Ž||PinPropagationDelay=0.000000E+000
|RECORD=2|OwnerIndex=50|OwnerPartId=1|FormalType=1|Electrical=4|PinConglomerate=56|PinLength=20|Location.X=484|Location.Y=947|Designator=6|SwapIDPart=Ž&Ž||PinPropagationDelay=0.000000E+000
|RECORD=2|OwnerIndex=50|OwnerPartId=1|FormalType=1|Electrical=4|PinConglomerate=56|PinLength=20|Location.X=484|Location.Y=892|Designator=5|SwapIDPart=Ž&Ž||PinPropagationDelay=0.000000E+000
|RECORD=6|OwnerIndex=50|IsNotAccesible=T|IndexInSheet=17|OwnerPartId=1|LineWidth=1|Color=16711680|LocationCount=4|X1=439|Y1=957|X2=439|Y2=937|X3=459|Y3=947|X4=439|Y4=957
|RECORD=12|OwnerIndex=50|IsNotAccesible=T|IndexInSheet=18|OwnerPartId=1|Location.X=449|Location.Y=954|Radius=1|Radius_Frac=79777|LineWidth=1|EndAngle=360.000|Color=16711680
|RECORD=6|OwnerIndex=50|IsNotAccesible=T|IndexInSheet=19|OwnerPartId=1|LineWidth=1|Color=16711680|LocationCount=4|X1=459|Y1=902|X2=459|Y2=882|X3=439|Y3=892|X4=459|Y4=902
|RECORD=12|OwnerIndex=50|IsNotAccesible=T|IndexInSheet=20|OwnerPartId=1|Location.X=449|Location.Y=899|Radius=1|Radius_Frac=79777|LineWidth=1|EndAngle=360.000|Color=16711680
|RECORD=6|OwnerIndex=50|IsNotAccesible=T|IndexInSheet=21|OwnerPartId=1|LineWidth=1|Color=16711680|LocationCount=3|X1=449|Y1=901|X2=449|Y2=917|X3=414|Y3=917
|RECORD=6|OwnerIndex=50|IsNotAccesible=T|IndexInSheet=22|OwnerPartId=1|LineWidth=1|Color=16711680|LocationCount=3|X1=449|Y1=956|X2=449|Y2=972|X3=414|Y3=972
|RECORD=6|OwnerIndex=50|IsNotAccesible=T|IndexInSheet=23|OwnerPartId=1|LineWidth=1|Color=16711680|LocationCount=2|X1=414|Y1=947|X2=439|Y2=947
|RECORD=6|OwnerIndex=50|IsNotAccesible=T|IndexInSheet=24|OwnerPartId=1|LineWidth=1|Color=16711680|LocationCount=2|X1=459|Y1=947|X2=484|Y2=947
|RECORD=6|OwnerIndex=50|IsNotAccesible=T|IndexInSheet=25|OwnerPartId=1|LineWidth=1|Color=16711680|LocationCount=2|X1=459|Y1=892|X2=484|Y2=892
|RECORD=6|OwnerIndex=50|IsNotAccesible=T|IndexInSheet=26|OwnerPartId=1|LineWidth=1|Color=16711680|LocationCount=2|X1=439|Y1=892|X2=414|Y2=892
|RECORD=34|OwnerIndex=50|IndexInSheet=-1|OwnerPartId=-1|Location.X=413|Location.Y=982|Color=8388608|FontID=1|Text=U8|Name=Designator|ReadOnlyState=1
|RECORD=41|OwnerIndex=50|IndexInSheet=-1|OwnerPartId=-1|Location.X=413|Location.Y=847|Color=8388608|FontID=1|Text=NC7WV125K8X|Name=Comment
|RECORD=44|OwnerIndex=50
|RECORD=45|OwnerIndex=88|IndexInSheet=-1|ModelName=SOP50P310X90-8N|ModelType=PCBLIB|DatafileCount=1|ModelDatafile0=C:\Users\<user>\Documents\AltiumLL\SamacSys.PcbLib|ModelDatafileEntity0=SOP50P310X90-8N|ModelDatafileKind0=PCBLIB|IsCurrent=T
|RECORD=46|OwnerIndex=89
|RECORD=48|OwnerIndex=89
|RECORD=17|IndexInSheet=35|OwnerPartId=-1|Style=4|ShowNetName=T|Location.X=704|Location.Y=817|Orientation=3|Color=128|FontID=1|Text=GND
|RECORD=1|LibReference=CN-1P-M-RF3|ComponentDescription=Ultra Miniature Coaxial Connector Jack, 60 V, 50 Ohm, -40 to 90 degC, RoHS, Tape and Reel|PartCount=2|DisplayModeCount=1|IndexInSheet=36|OwnerPartId=-1|Location.X=634|Location.Y=967|CurrentPartId=1|LibraryPath=*|SourceLibraryName=Altium Content Vault|TargetFileName=*|AreaColor=11599871|Color=128|PartIDLocked=T|DesignItemId=CMP-2000-07505-1|AllPinCount=3
|RECORD=8|OwnerIndex=93|IsNotAccesible=T|OwnerPartId=1|Location.X=654|Location.Y=947|Radius=20|SecondaryRadius=20|LineWidth=1|Color=16711680|AreaColor=16777215
|RECORD=8|OwnerIndex=93|IsNotAccesible=T|IndexInSheet=1|OwnerPartId=1|Location.X=654|Location.Y=947|Radius=4|SecondaryRadius=4|LineWidth=1|Color=16711680|AreaColor=16777215
|RECORD=2|OwnerIndex=93|OwnerPartId=1|FormalType=1|Electrical=4|PinConglomerate=51|PinLength=10|Location.X=644|Location.Y=927|Name=1|Designator=1|PinPropagationDelay=0.000000E+000
|RECORD=2|OwnerIndex=93|OwnerPartId=1|FormalType=1|Electrical=4|PinConglomerate=50|PinLength=10|Location.X=634|Location.Y=947|Name=2|Designator=2|PinPropagationDelay=0.000000E+000
|RECORD=2|OwnerIndex=93|OwnerPartId=1|FormalType=1|Electrical=4|PinConglomerate=51|PinLength=10|Location.X=664|Location.Y=927|Name=3|Designator=3|PinPropagationDelay=0.000000E+000
|RECORD=6|OwnerIndex=93|IsNotAccesible=T|IndexInSheet=5|OwnerPartId=1|LineWidth=1|Color=16711680|LocationCount=5|X1=634|Y1=927|X2=634|Y2=967|X3=674|Y3=967|X4=674|Y4=927|X5=634|Y5=927
|RECORD=6|OwnerIndex=93|IsNotAccesible=T|IndexInSheet=6|OwnerPartId=1|LineWidth=1|Color=16711680|LocationCount=2|X1=634|Y1=947|X2=650|Y2=947
|RECORD=41|OwnerIndex=93|IndexInSheet=7|OwnerPartId=-1|Location.X=622|Location.Y=968|Color=8388608|FontID=1|IsHidden=T|Text=Straight|Name=Orientation
|RECORD=41|OwnerIndex=93|IndexInSheet=8|OwnerPartId=-1|Location.X=622|Location.Y=968|Color=8388608|FontID=1|IsHidden=T|Text=Female|Name=Gender
|RECORD=41|OwnerIndex=93|IndexInSheet=9|OwnerPartId=-1|Location.X=622|Location.Y=968|Color=8388608|FontID=1|IsHidden=T|Text=Vertical|Name=PCB Mounting Orientation
|RECORD=41|OwnerIndex=93|IndexInSheet=10|OwnerPartId=-1|Location.X=622|Location.Y=968|Color=8388608|FontID=1|IsHidden=T|Text=SurfaceMount|Name=Mount
|RECORD=41|OwnerIndex=93|IndexInSheet=11|OwnerPartId=-1|Location.X=622|Location.Y=968|Color=8388608|FontID=1|IsHidden=T|Text=3mm|Name=Length
|RECORD=41|OwnerIndex=93|IndexInSheet=12|OwnerPartId=-1|Location.X=622|Location.Y=968|Color=8388608|FontID=1|IsHidden=T|Text=TapeandReel|Name=Packaging
|RECORD=41|OwnerIndex=93|IndexInSheet=13|OwnerPartId=-1|Location.X=622|Location.Y=968|Color=8388608|FontID=1|IsHidden=T|Text=Jack|Name=Connector Type
|RECORD=41|OwnerIndex=93|IndexInSheet=14|OwnerPartId=-1|Location.X=622|Location.Y=968|Color=8388608|FontID=1|IsHidden=T|Text=LeadFree|Name=Lead Free
|RECORD=41|OwnerIndex=93|IndexInSheet=15|OwnerPartId=-1|Location.X=622|Location.Y=968|Color=8388608|FontID=1|IsHidden=T|Text=1|Name=Package Quantity
|RECORD=41|OwnerIndex=93|IndexInSheet=16|OwnerPartId=-1|Location.X=622|Location.Y=968|Color=8388608|FontID=1|IsHidden=T|Text=SMD/SMT|Name=Termination
|RECORD=41|OwnerIndex=93|IndexInSheet=17|OwnerPartId=-1|Location.X=622|Location.Y=968|Color=8388608|FontID=1|IsHidden=T|Text=CopperAlloy|Name=Contact Material
|RECORD=41|OwnerIndex=93|IndexInSheet=18|OwnerPartId=-1|Location.X=622|Location.Y=968|Color=8388608|FontID=1|IsHidden=T|Text=Pull|Name=Fastening Type
|RECORD=41|OwnerIndex=93|IndexInSheet=19|OwnerPartId=-1|Location.X=622|Location.Y=968|Color=8388608|FontID=1|IsHidden=T|Text=true|Name=RoHSCompliant
|RECORD=41|OwnerIndex=93|IndexInSheet=20|OwnerPartId=-1|Location.X=622|Location.Y=968|Color=8388608|FontID=1|IsHidden=T|Text=LiquidCrystalPolymer|Name=Body Material
|RECORD=41|OwnerIndex=93|IndexInSheet=21|OwnerPartId=-1|Location.X=622|Location.Y=968|Color=8388608|FontID=1|IsHidden=T|Text=SMD/SMT|Name=Case\/Package
|RECORD=41|OwnerIndex=93|IndexInSheet=22|OwnerPartId=-1|Location.X=622|Location.Y=968|Color=8388608|FontID=1|IsHidden=T|Text=90degC|Name=Max Operating Temperature
|RECORD=41|OwnerIndex=93|IndexInSheet=23|OwnerPartId=-1|Location.X=622|Location.Y=968|Color=8388608|FontID=1|IsHidden=T|Text=50Ohm|Name=Impedance
|RECORD=41|OwnerIndex=93|IndexInSheet=24|OwnerPartId=-1|Location.X=622|Location.Y=968|Color=8388608|FontID=7|IsHidden=T|Text=http://www.te.com/commerce/DocumentDelivery/DDEController?Action=srchrtrv&DocNm=1909763&DocType=Customer+Drawing&DocLang=English|Name=Datasheet URL
|RECORD=41|OwnerIndex=93|IndexInSheet=25|OwnerPartId=-1|Location.X=622|Location.Y=968|Color=8388608|FontID=1|IsHidden=T|Text=Gold|Name=Contact Plating
|RECORD=41|OwnerIndex=93|IndexInSheet=26|OwnerPartId=-1|Location.X=622|Location.Y=968|Color=8388608|FontID=1|IsHidden=T|Text=SurfaceMount|Name=Mounting Technology
|RECORD=41|OwnerIndex=93|IndexInSheet=27|OwnerPartId=-1|Location.X=622|Location.Y=968|Color=8388608|FontID=1|IsHidden=T|Text=6GHz|Name=Max Frequency
|RECORD=41|OwnerIndex=93|IndexInSheet=28|OwnerPartId=-1|Location.X=622|Location.Y=968|Color=8388608|FontID=1|IsHidden=T|Text=TECO-1909763-1|Name=Package Reference
|RECORD=41|OwnerIndex=93|IndexInSheet=29|OwnerPartId=-1|Location.X=622|Location.Y=968|Color=8388608|FontID=1|IsHidden=T|Text=Thermoplastic|Name=Insulation Material
|RECORD=41|OwnerIndex=93|IndexInSheet=30|OwnerPartId=-1|Location.X=622|Location.Y=968|Color=8388608|FontID=1|IsHidden=T|Text=-40degC|Name=Min Operating Temperature
|RECORD=41|OwnerIndex=93|IndexInSheet=31|OwnerPartId=-1|Location.X=622|Location.Y=968|Color=8388608|FontID=7|IsHidden=T|Text=http://www.te.com/|Name=Manufacturer URL
|RECORD=41|OwnerIndex=93|IndexInSheet=32|OwnerPartId=-1|Location.X=622|Location.Y=968|Color=8388608|FontID=1|IsHidden=T|Text=Gold|Name=Body Plating
|RECORD=41|OwnerIndex=93|IndexInSheet=33|OwnerPartId=-1|Location.X=622|Location.Y=968|Color=8388608|FontID=1|IsHidden=T|Text=Polymer|Name=Dielectric Material
|RECORD=41|OwnerIndex=93|IndexInSheet=34|OwnerPartId=-1|Location.X=622|Location.Y=968|Color=8388608|FontID=1|IsHidden=T|Text=TE Connectivity|Name=Manufacturer
|RECORD=41|OwnerIndex=93|IndexInSheet=35|OwnerPartId=-1|Location.X=622|Location.Y=968|Color=8388608|FontID=1|IsHidden=T|Text=Compliant|Name=ELV
|RECORD=41|OwnerIndex=93|IndexInSheet=36|OwnerPartId=-1|Location.X=622|Location.Y=968|Color=8388608|FontID=1|IsHidden=T|Text=Rev. B2, 11/2015|Name=Datasheet Version
|RECORD=41|OwnerIndex=93|IndexInSheet=37|OwnerPartId=-1|Location.X=622|Location.Y=968|Color=8388608|FontID=1|IsHidden=T|Text=No|Name=Radiation Hardening
|RECORD=41|OwnerIndex=93|IndexInSheet=38|OwnerPartId=-1|Location.X=622|Location.Y=968|Color=8388608|FontID=1|IsHidden=T|Text=3-Pin Surface Mount Device, Body 2.6 x 2.6 mm|Name=Package Description
|RECORD=41|OwnerIndex=93|IndexInSheet=39|OwnerPartId=-1|Location.X=622|Location.Y=968|Color=8388608|FontID=1|IsHidden=T|Text=Beige|Name=Housing Colour
|RECORD=34|OwnerIndex=93|IndexInSheet=-1|OwnerPartId=-1|Location.X=633|Location.Y=968|Color=8388608|FontID=1|Text=J1|Name=Designator|ReadOnlyState=1
|RECORD=41|OwnerIndex=93|IndexInSheet=-1|OwnerPartId=-1|Location.X=684|Location.Y=927|Color=8388608|FontID=1|Text=1909763-1|Name=Comment
|RECORD=44|OwnerIndex=93
|RECORD=45|OwnerIndex=139|IndexInSheet=-1|Description=SMD, 3-Leads, Body 2.6x2.6mm, Height 1.25mm|UseComponentLibrary=T|ModelName=TECO-1909763-1_V|ModelType=PCBLIB|DatafileCount=1|ModelDatafileEntity0=TECO-1909763-1_V|ModelDatafileKind0=PCBLib|IsCurrent=T|DatalinksLocked=T|DatabaseDatalinksLocked=T
|RECORD=46|OwnerIndex=140
|RECORD=48|OwnerIndex=140
|RECORD=41|OwnerIndex=142|IndexInSheet=-1|OwnerPartId=-1|Color=8388608|FontID=1|Text=2D|Name=Available Preview Images
|RECORD=1|LibReference=CN-S-4F-RF5|ComponentDescription=Coaxial connector, 50 Ohm, -65 to 165 degC, 5-Pin THD, RoHS, Bulk|PartCount=2|DisplayModeCount=1|IndexInSheet=37|OwnerPartId=-1|Location.X=634|Location.Y=887|CurrentPartId=1|LibraryPath=*|SourceLibraryName=Altium Content Vault|TargetFileName=*|AreaColor=11599871|Color=128|PartIDLocked=T|DesignItemId=CMP-2000-05705-1|AllPinCount=5
|RECORD=2|OwnerIndex=144|OwnerPartId=1|FormalType=1|Electrical=4|PinConglomerate=51|PinLength=10|Location.X=674|Location.Y=847|Name=5|Designator=5|SwapIDPart=Ž&Ž1|PinPropagationDelay=0.000000E+000
|RECORD=8|OwnerIndex=144|IsNotAccesible=T|IndexInSheet=1|OwnerPartId=1|Location.X=654|Location.Y=867|Radius=20|SecondaryRadius=20|LineWidth=1|Color=16711680|AreaColor=16777215
|RECORD=8|OwnerIndex=144|IsNotAccesible=T|IndexInSheet=2|OwnerPartId=1|Location.X=654|Location.Y=867|Radius=4|SecondaryRadius=4|LineWidth=1|Color=16711680|AreaColor=16777215
|RECORD=2|OwnerIndex=144|OwnerPartId=1|FormalType=1|Electrical=4|PinConglomerate=50|PinLength=10|Location.X=634|Location.Y=867|Name=1|Designator=1|PinPropagationDelay=0.000000E+000
|RECORD=2|OwnerIndex=144|OwnerPartId=1|FormalType=1|Electrical=4|PinConglomerate=51|PinLength=10|Location.X=644|Location.Y=847|Name=2|Designator=2|PinPropagationDelay=0.000000E+000
|RECORD=2|OwnerIndex=144|OwnerPartId=1|FormalType=1|Electrical=4|PinConglomerate=51|PinLength=10|Location.X=654|Location.Y=847|Name=3|Designator=3|PinPropagationDelay=0.000000E+000
|RECORD=2|OwnerIndex=144|OwnerPartId=1|FormalType=1|Electrical=4|PinConglomerate=51|PinLength=10|Location.X=664|Location.Y=847|Name=4|Designator=4|PinPropagationDelay=0.000000E+000
|RECORD=6|OwnerIndex=144|IsNotAccesible=T|IndexInSheet=7|OwnerPartId=1|LineWidth=1|Color=16711680|LocationCount=5|X1=634|Y1=847|X2=634|Y2=887|X3=674|Y3=887|X4=674|Y4=847|X5=634|Y5=847
|RECORD=6|OwnerIndex=144|IsNotAccesible=T|IndexInSheet=8|OwnerPartId=1|LineWidth=1|Color=16711680|LocationCount=2|X1=634|Y1=867|X2=650|Y2=867
|RECORD=41|OwnerIndex=144|IndexInSheet=9|OwnerPartId=-1|Location.X=622|Location.Y=888|Color=8388608|FontID=1|IsHidden=T|Text=ThroughHole|Name=Mounting Technology
|RECORD=41|OwnerIndex=144|IndexInSheet=10|OwnerPartId=-1|Location.X=622|Location.Y=888|Color=8388608|FontID=1|IsHidden=T|Text=ThroughHole,RightAngle|Name=Mounting Type
|RECORD=41|OwnerIndex=144|IndexInSheet=11|OwnerPartId=-1|Location.X=622|Location.Y=888|Color=8388608|FontID=1|IsHidden=T|Text=-|Name=Cable Group
|RECORD=41|OwnerIndex=144|IndexInSheet=12|OwnerPartId=-1|Location.X=622|Location.Y=888|Color=8388608|FontID=1|IsHidden=T|Text=901-143-6RFXMountingHole|Name=Catalog Drawings
|RECORD=41|OwnerIndex=144|IndexInSheet=13|OwnerPartId=-1|Location.X=622|Location.Y=888|Color=8388608|FontID=1|IsHidden=T|Text=901-143-6RFX.igs|Name=3D Model
|RECORD=41|OwnerIndex=144|IndexInSheet=14|OwnerPartId=-1|Location.X=622|Location.Y=888|Color=8388608|FontID=1|IsHidden=T|Text=-|Name=Series
|RECORD=41|OwnerIndex=144|IndexInSheet=15|OwnerPartId=-1|Location.X=622|Location.Y=888|Color=8388608|FontID=1|IsHidden=T|Text=5-Pin Through Hole Device, Body 7 x 7 mm, Pitch 2.54 mm|Name=Package Description
|RECORD=41|OwnerIndex=144|IndexInSheet=16|OwnerPartId=-1|Location.X=622|Location.Y=888|Color=8388608|FontID=1|IsHidden=T|Text=901-143-6RFX|Name=Package Reference
|RECORD=41|OwnerIndex=144|IndexInSheet=17|OwnerPartId=-1|Location.X=622|Location.Y=888|Color=8388608|FontID=1|IsHidden=T|Text=Brass|Name=Body Material
|RECORD=41|OwnerIndex=144|IndexInSheet=18|OwnerPartId=-1|Location.X=622|Location.Y=888|Color=8388608|FontID=1|IsHidden=T|Text=-|Name=Voltage Rating
|RECORD=41|OwnerIndex=144|IndexInSheet=19|OwnerPartId=-1|Location.X=622|Location.Y=888|Color=8388608|FontID=1|IsHidden=T|Text=1|Name=Standard Package
|RECORD=41|OwnerIndex=144|IndexInSheet=20|OwnerPartId=-1|Location.X=622|Location.Y=888|Color=8388608|FontID=1|IsHidden=T|Text=Jack,FemaleSocket|Name=Connector Type
|RECORD=41|OwnerIndex=144|IndexInSheet=21|OwnerPartId=-1|Location.X=622|Location.Y=888|Color=8388608|FontID=1|IsHidden=T|Text=Threaded|Name=Fastening Type
|RECORD=41|OwnerIndex=144|IndexInSheet=22|OwnerPartId=-1|Location.X=622|Location.Y=888|Color=8388608|FontID=1|IsHidden=T|Text=Gold|Name=Housing Color
|RECORD=41|OwnerIndex=144|IndexInSheet=23|OwnerPartId=-1|Location.X=622|Location.Y=888|Color=8388608|FontID=1|IsHidden=T|Text=Solder|Name=Shield Termination
|RECORD=41|OwnerIndex=144|IndexInSheet=24|OwnerPartId=-1|Location.X=622|Location.Y=888|Color=8388608|FontID=1|IsHidden=T|Text=901-143-6-RFX9011436RFXARFX1232|Name=Other Names
|RECORD=41|OwnerIndex=144|IndexInSheet=25|OwnerPartId=-1|Location.X=622|Location.Y=888|Color=8388608|FontID=7|IsHidden=T|Text=http://www.amphenolrf.com/downloads/dl/file/id/2712/product/3102/901_143_6rfx_customer_drawing.pdf|Name=Datasheet URL
|RECORD=41|OwnerIndex=144|IndexInSheet=26|OwnerPartId=-1|Location.X=622|Location.Y=888|Color=8388608|FontID=1|IsHidden=T|Text=CoaxialConnectors(RF)|Name=Family
|RECORD=41|OwnerIndex=144|IndexInSheet=27|OwnerPartId=-1|Location.X=622|Location.Y=888|Color=8388608|FontID=1|IsHidden=T|Text=SMA,RFX|Name=Online Catalog
|RECORD=41|OwnerIndex=144|IndexInSheet=28|OwnerPartId=-1|Location.X=622|Location.Y=888|Color=8388608|FontID=1|IsHidden=T|Text=18GHz|Name=Frequency - Max
|RECORD=41|OwnerIndex=144|IndexInSheet=29|OwnerPartId=-1|Location.X=622|Location.Y=888|Color=8388608|FontID=1|IsHidden=T|Text=Solder|Name=Contact Termination
|RECORD=41|OwnerIndex=144|IndexInSheet=30|OwnerPartId=-1|Location.X=622|Location.Y=888|Color=8388608|FontID=7|IsHidden=T|Text=http://www.amphenol.com/|Name=Manufacturer URL
|RECORD=41|OwnerIndex=144|IndexInSheet=31|OwnerPartId=-1|Location.X=622|Location.Y=888|Color=8388608|FontID=1|IsHidden=T|Text=Amphenol|Name=Manufacturer
|RECORD=41|OwnerIndex=144|IndexInSheet=32|OwnerPartId=-1|Location.X=622|Location.Y=888|Color=8388608|FontID=1|IsHidden=T|Text=-65°C~165°C|Name=Operating Temperature
|RECORD=41|OwnerIndex=144|IndexInSheet=33|OwnerPartId=-1|Location.X=622|Location.Y=888|Color=8388608|FontID=1|IsHidden=T|Text=Connectors,Interconnects|Name=Category
|RECORD=41|OwnerIndex=144|IndexInSheet=34|OwnerPartId=-1|Location.X=622|Location.Y=888|Color=8388608|FontID=1|IsHidden=T|Text=Bulk|Name=Packaging
|RECORD=41|OwnerIndex=144|IndexInSheet=35|OwnerPartId=-1|Location.X=622|Location.Y=888|Color=8388608|FontID=1|IsHidden=T|Text=Gold|Name=Body Finish
|RECORD=41|OwnerIndex=144|IndexInSheet=36|OwnerPartId=-1|Location.X=622|Location.Y=888|Color=8388608|FontID=1|IsHidden=T|Text=Polytetrafluoroethylene(PTFE)|Name=Dielectric Material
|RECORD=41|OwnerIndex=144|IndexInSheet=37|OwnerPartId=-1|Location.X=622|Location.Y=888|Color=8388608|FontID=1|IsHidden=T|Text=BerylliumCopper|Name=Center Contact Material
|RECORD=41|OwnerIndex=144|IndexInSheet=38|OwnerPartId=-1|Location.X=622|Location.Y=888|Color=8388608|FontID=1|IsHidden=T|Text=50Ohm|Name=Impedance
|RECORD=41|OwnerIndex=144|IndexInSheet=39|OwnerPartId=-1|Location.X=622|Location.Y=888|Color=8388608|FontID=1|IsHidden=T|Text=-|Name=Features
|RECORD=41|OwnerIndex=144|IndexInSheet=40|OwnerPartId=-1|Location.X=622|Location.Y=888|Color=8388608|FontID=1|IsHidden=T|Text=SMA|Name=Connector Style
|RECORD=41|OwnerIndex=144|IndexInSheet=41|OwnerPartId=-1|Location.X=622|Location.Y=888|Color=8388608|FontID=1|IsHidden=T|Text=Gold|Name=Center Contact Plating
|RECORD=41|OwnerIndex=144|IndexInSheet=42|OwnerPartId=-1|Location.X=622|Location.Y=888|Color=8388608|FontID=1|IsHidden=T|Text=Rev. C, 06/2010|Name=Datasheet Version
|RECORD=41|OwnerIndex=144|IndexInSheet=43|OwnerPartId=-1|Location.X=622|Location.Y=888|Color=8388608|FontID=1|IsHidden=T|Text=-|Name=Ingress Protection
|RECORD=34|OwnerIndex=144|IndexInSheet=-1|OwnerPartId=-1|Location.X=633|Location.Y=888|Color=8388608|FontID=1|Text=AN1|Name=Designator|ReadOnlyState=1
|RECORD=41|OwnerIndex=144|IndexInSheet=-1|OwnerPartId=-1|Location.X=684|Location.Y=837|Color=8388608|FontID=1|Text=RF2-49B-T-00-50-G-HDW|Name=Comment
|RECORD=44|OwnerIndex=144
|RECORD=45|OwnerIndex=196|IndexInSheet=-1|Description=THD, 5-Leads, Body 7x7mm, Pitch 2.54mm|UseComponentLibrary=T|ModelName=AMPH-901-143-6RFX_V|ModelType=PCBLIB|DatafileCount=1|ModelDatafileEntity0=AMPH-901-143-6RFX_V|ModelDatafileKind0=PCBLib|IsCurrent=T|DatalinksLocked=T|DatabaseDatalinksLocked=T
|RECORD=46|OwnerIndex=197
|RECORD=48|OwnerIndex=197
|RECORD=41|OwnerIndex=199|IndexInSheet=-1|OwnerPartId=-1|Color=8388608|FontID=1|Text=2D|Name=Available Preview Images
|RECORD=17|IndexInSheet=38|OwnerPartId=-1|Style=4|ShowNetName=T|Location.X=704|Location.Y=907|Orientation=3|Color=128|FontID=1|Text=GND
|RECORD=1|LibReference=RES-2|ComponentDescription=General Purpose Chip Resistor, 49.9 Ohm, +/- 1%, -55 to 155 degC, 0603 (1608 Metric), RoHS, Tape and Reel|PartCount=2|DisplayModeCount=1|IndexInSheet=39|OwnerPartId=-1|Location.X=539|Location.Y=947|CurrentPartId=1|LibraryPath=*|SourceLibraryName=Altium Content Vault|TargetFileName=*|AreaColor=11599871|Color=128|PartIDLocked=T|DesignItemId=CMP-1659-00036-1|AllPinCount=2
|RECORD=2|OwnerIndex=202|OwnerPartId=1|FormalType=1|Electrical=4|PinConglomerate=32|PinLength=10|Location.X=559|Location.Y=947|Name=2|Designator=2|PinPropagationDelay=0.000000E+000
|RECORD=2|OwnerIndex=202|OwnerPartId=1|FormalType=1|Electrical=4|PinConglomerate=34|PinLength=10|Location.X=539|Location.Y=947|Name=1|Designator=1|PinPropagationDelay=0.000000E+000
|RECORD=6|OwnerIndex=202|IsNotAccesible=T|IndexInSheet=2|OwnerPartId=1|LineWidth=1|Color=16711680|LocationCount=10|X1=559|Y1=947|X2=555|Y2=947|X3=554|Y3=945|X4=552|Y4=949|X5=550|Y5=945|X6=548|Y6=949|X7=546|Y7=945|X8=544|Y8=949|X9=543|Y9=947|X10=539|Y10=947
|RECORD=41|OwnerIndex=202|IndexInSheet=3|OwnerPartId=-1|Location.X=527|Location.Y=962|Color=8388608|FontID=1|IsHidden=T|Text=0603|Name=PackageReference
|RECORD=41|OwnerIndex=202|IndexInSheet=4|OwnerPartId=-1|Location.X=527|Location.Y=962|Color=8388608|FontID=1|IsHidden=T|Text=Tray|Name=Packaging
|RECORD=41|OwnerIndex=202|IndexInSheet=5|OwnerPartId=-1|Location.X=527|Location.Y=962|Color=8388608|FontID=1|IsHidden=T|Text=Datasheet|Name=ComponentLink2Description
|RECORD=41|OwnerIndex=202|IndexInSheet=6|OwnerPartId=-1|Location.X=527|Location.Y=962|Color=8388608|FontID=1|IsHidden=T|Text=Manufacturer URL|Name=ComponentLink1Description
|RECORD=41|OwnerIndex=202|IndexInSheet=7|OwnerPartId=-1|Location.X=527|Location.Y=962|Color=8388608|FontID=7|IsHidden=T|Text=https://datasheet.ciiva.com/11808/0900766b80f96399-11808223.pdf|Name=ComponentLink2URL
|RECORD=41|OwnerIndex=202|IndexInSheet=8|OwnerPartId=-1|Location.X=527|Location.Y=962|Color=8388608|FontID=1|IsHidden=T|Text=true|Name=RoHSCompliant
|RECORD=41|OwnerIndex=202|IndexInSheet=9|OwnerPartId=-1|Location.X=527|Location.Y=962|Color=8388608|FontID=1|IsHidden=T|Text=85 degC|Name=Max Operating Temperature
|RECORD=41|OwnerIndex=202|IndexInSheet=10|OwnerPartId=-1|Location.X=527|Location.Y=962|Color=8388608|FontID=1|IsHidden=T|Text=3.63 V|Name=Max Supply Voltage
|RECORD=41|OwnerIndex=202|IndexInSheet=11|OwnerPartId=-1|Location.X=527|Location.Y=962|Color=8388608|FontID=7|IsHidden=T|Text=http://www.yageo.com/|Name=ComponentLink1URL
|RECORD=41|OwnerIndex=202|IndexInSheet=12|OwnerPartId=-1|Location.X=527|Location.Y=962|Color=8388608|FontID=1|IsHidden=T|Text=2-Pin Surface Mount Device, Body 1.6 x 0.8 mm|Name=PackageDescription
|RECORD=41|OwnerIndex=202|IndexInSheet=13|OwnerPartId=-1|Location.X=527|Location.Y=962|Color=8388608|FontID=1|IsHidden=T|Text=LQFP|Name=Case\Package
|RECORD=41|OwnerIndex=202|IndexInSheet=14|OwnerPartId=-1|Location.X=527|Location.Y=962|Color=8388608|FontID=1|IsHidden=T|Text=Rev. 4, 04/2009|Name=DatasheetVersion
|RECORD=41|OwnerIndex=202|IndexInSheet=15|OwnerPartId=-1|Location.X=527|Location.Y=962|Color=8388608|FontID=1|IsHidden=T|Text=-40 degC|Name=Min Operating Temperature
|RECORD=41|OwnerIndex=202|IndexInSheet=16|OwnerPartId=-1|Location.X=527|Location.Y=962|Color=8388608|FontID=1|IsHidden=T|Text=SPI|Name=Interface
|RECORD=41|OwnerIndex=202|IndexInSheet=17|OwnerPartId=-1|Location.X=527|Location.Y=962|Color=8388608|FontID=1|IsHidden=T|Text=250|Name=Package Quantity
|RECORD=41|OwnerIndex=202|IndexInSheet=18|OwnerPartId=-1|Location.X=527|Location.Y=962|Color=8388608|FontID=1|IsHidden=T|Text=2.97 V|Name=Min Supply Voltage
|RECORD=41|OwnerIndex=202|IndexInSheet=19|OwnerPartId=-1|Location.X=527|Location.Y=962|Color=8388608|FontID=1|IsHidden=T|Text=48|Name=Pins
|RECORD=34|OwnerIndex=202|IndexInSheet=-1|OwnerPartId=-1|Location.X=538|Location.Y=950|Color=8388608|FontID=1|Text=R25|Name=Designator|ReadOnlyState=1
|RECORD=41|OwnerIndex=202|IndexInSheet=-1|OwnerPartId=-1|Location.X=538|Location.Y=934|Color=8388608|FontID=1|Text=49.9R|Name=Comment
|RECORD=44|OwnerIndex=202
|RECORD=45|OwnerIndex=227|IndexInSheet=-1|Description=Chip Resistor, 2-Leads, Body 1.70x0.90mm, IPC Medium Density|UseComponentLibrary=T|ModelName=RESC1608X55X25NL10T15|ModelType=PCBLIB|DatafileCount=1|ModelDatafileEntity0=RESC1608X55X25NL10T15|ModelDatafileKind0=PCBLib|IsCurrent=T|DatalinksLocked=T|DatabaseDatalinksLocked=T
|RECORD=46|OwnerIndex=228
|RECORD=48|OwnerIndex=228
|RECORD=41|OwnerIndex=230|IndexInSheet=-1|OwnerPartId=-1|Color=8388608|FontID=1|IsHidden=T|Text=2D|Name=Available Preview Images
|RECORD=45|OwnerIndex=227|IndexInSheet=-1|Description=Chip Resistor, 2-Leads, Body 1.70x0.90mm, IPC Low Density|UseComponentLibrary=T|ModelName=RESC1608X55X25ML10T15|ModelType=PCBLIB|DatafileCount=1|ModelDatafileEntity0=RESC1608X55X25ML10T15|ModelDatafileKind0=PCBLib|DatalinksLocked=T|DatabaseDatalinksLocked=T
|RECORD=46|OwnerIndex=232
|RECORD=48|OwnerIndex=232
|RECORD=41|OwnerIndex=234|IndexInSheet=-1|OwnerPartId=-1|Color=8388608|FontID=1|IsHidden=T|Text=2D|Name=Available Preview Images
|RECORD=45|OwnerIndex=227|IndexInSheet=-1|Description=Chip Resistor, 2-Leads, Body 1.70x0.90mm, IPC High Density|UseComponentLibrary=T|ModelName=RESC1608X55X25LL10T15|ModelType=PCBLIB|DatafileCount=1|ModelDatafileEntity0=RESC1608X55X25LL10T15|ModelDatafileKind0=PCBLib|DatalinksLocked=T|DatabaseDatalinksLocked=T
|RECORD=46|OwnerIndex=236
|RECORD=48|OwnerIndex=236
|RECORD=41|OwnerIndex=238|IndexInSheet=-1|OwnerPartId=-1|Color=8388608|FontID=1|IsHidden=T|Text=2D|Name=Available Preview Images
|RECORD=17|IndexInSheet=40|OwnerPartId=-1|ShowNetName=T|Location.X=264|Location.Y=947|Orientation=2|Color=255|FontID=1|Text=ANT1_OUT|IsCrossSheetConnector=T
|RECORD=41|OwnerIndex=240|OwnerPartId=-1|Location.X=202|Location.X_Frac=7849|Location.Y=947|Orientation=2|Justification=3|Color=8388608|FontID=1|Text=FPGA[4A]|Name=CrossRef|ReadOnlyState=3
|RECORD=1|LibReference=RES-2|ComponentDescription=Precision Thick Film Chip Resistor, 4.7 KOhm, +/- 1%, -55 to 155 degC, 0603 (1608 Metric), RoHS, Tape and Reel ERJ-3EKF4701V|PartCount=2|DisplayModeCount=1|IndexInSheet=41|OwnerPartId=-1|Location.X=274|Location.Y=1007|Orientation=1|CurrentPartId=1|LibraryPath=*|SourceLibraryName=Altium Content Vault|TargetFileName=*|AreaColor=11599871|Color=128|PartIDLocked=T|DesignItemId=CMP-1012-00586-3|AllPinCount=2
|RECORD=2|OwnerIndex=242|OwnerPartId=1|FormalType=1|Electrical=4|PinConglomerate=33|PinLength=10|Location.X=274|Location.Y=1027|Name=2|Designator=2|PinPropagationDelay=0.000000E+000
|RECORD=2|OwnerIndex=242|OwnerPartId=1|FormalType=1|Electrical=4|PinConglomerate=35|PinLength=10|Location.X=274|Location.Y=1007|Name=1|Designator=1|PinPropagationDelay=0.000000E+000
|RECORD=6|OwnerIndex=242|IsNotAccesible=T|IndexInSheet=2|OwnerPartId=1|LineWidth=1|Color=16711680|LocationCount=10|X1=274|Y1=1027|X2=274|Y2=1023|X3=276|Y3=1022|X4=272|Y4=1020|X5=276|Y5=1018|X6=272|Y6=1016|X7=276|Y7=1014|X8=272|Y8=1012|X9=274|Y9=1011|X10=274|Y10=1007
|RECORD=41|OwnerIndex=242|IndexInSheet=3|OwnerPartId=-1|Location.X=271|Location.Y=1039|Color=8388608|FontID=1|IsHidden=T|Text=220 Ohm|Name=Resistance
|RECORD=41|OwnerIndex=242|IndexInSheet=4|OwnerPartId=-1|Location.X=271|Location.Y=1039|Color=8388608|FontID=1|IsHidden=T|Text=0603|Name=PackageReference
|RECORD=41|OwnerIndex=242|IndexInSheet=5|OwnerPartId=-1|Location.X=271|Location.Y=1039|Color=8388608|FontID=1|IsHidden=T|Text=50 V|Name=Voltage Rating
|RECORD=41|OwnerIndex=242|IndexInSheet=6|OwnerPartId=-1|Location.X=271|Location.Y=1039|Color=8388608|FontID=1|IsHidden=T|Text=125 degC|Name=Max Operating Temperature
|RECORD=41|OwnerIndex=242|IndexInSheet=7|OwnerPartId=-1|Location.X=271|Location.Y=1039|Color=8388608|FontID=1|IsHidden=T|Text=4|Name=Elements
|RECORD=41|OwnerIndex=242|IndexInSheet=8|OwnerPartId=-1|Location.X=271|Location.Y=1039|Color=8388608|FontID=1|IsHidden=T|Text=No SVHC|Name=REACH SVHC
|RECORD=41|OwnerIndex=242|IndexInSheet=9|OwnerPartId=-1|Location.X=271|Location.Y=1039|Color=8388608|FontID=1|IsHidden=T|Text=0.063 inch|Name=Width
|RECORD=41|OwnerIndex=242|IndexInSheet=10|OwnerPartId=-1|Location.X=271|Location.Y=1039|Color=8388608|FontID=1|IsHidden=T|Text=1205|Name=Case\Package
|RECORD=41|OwnerIndex=242|IndexInSheet=11|OwnerPartId=-1|Location.X=271|Location.Y=1039|Color=8388608|FontID=1|IsHidden=T|Text=0.126 inch|Name=Length
|RECORD=41|OwnerIndex=242|IndexInSheet=12|OwnerPartId=-1|Location.X=271|Location.Y=1039|Color=8388608|FontID=1|IsHidden=T|Text=0.024 inch|Name=Height
|RECORD=41|OwnerIndex=242|IndexInSheet=13|OwnerPartId=-1|Location.X=271|Location.Y=1039|Color=8388608|FontID=1|IsHidden=T|Text=Surface Mount|Name=Mount
|RECORD=41|OwnerIndex=242|IndexInSheet=14|OwnerPartId=-1|Location.X=271|Location.Y=1039|Color=8388608|FontID=1|IsHidden=T|Text=1|Name=Package Quantity
|RECORD=41|OwnerIndex=242|IndexInSheet=15|OwnerPartId=-1|Location.X=271|Location.Y=1039|Color=8388608|FontID=1|IsHidden=T|Text=Apr-15|Name=DatasheetVersion
|RECORD=41|OwnerIndex=242|IndexInSheet=16|OwnerPartId=-1|Location.X=271|Location.Y=1039|Color=8388608|FontID=1|IsHidden=T|Text=Manufacturer URL|Name=ComponentLink1Description
|RECORD=41|OwnerIndex=242|IndexInSheet=17|OwnerPartId=-1|Location.X=271|Location.Y=1039|Color=8388608|FontID=1|IsHidden=T|Text=-55 degC|Name=Min Operating Temperature
|RECORD=41|OwnerIndex=242|IndexInSheet=18|OwnerPartId=-1|Location.X=271|Location.Y=1039|Color=8388608|FontID=1|IsHidden=T|Text=Tape and Reel|Name=Packaging
|RECORD=41|OwnerIndex=242|IndexInSheet=19|OwnerPartId=-1|Location.X=271|Location.Y=1039|Color=8388608|FontID=1|IsHidden=T|Text=No|Name=Radiation Hardening
|RECORD=41|OwnerIndex=242|IndexInSheet=20|OwnerPartId=-1|Location.X=271|Location.Y=1039|Color=8388608|FontID=7|IsHidden=T|Text=http://industrial.panasonic.com/cdbs/www-data/pdf/RDA0000/AOA0000C86.pdf|Name=ComponentLink2URL
|RECORD=41|OwnerIndex=242|IndexInSheet=21|OwnerPartId=-1|Location.X=271|Location.Y=1039|Color=8388608|FontID=1|IsHidden=T|Text=3216|Name=Case Code (Metric)
|RECORD=41|OwnerIndex=242|IndexInSheet=22|OwnerPartId=-1|Location.X=271|Location.Y=1039|Color=8388608|FontID=1|IsHidden=T|Text=8|Name=Pins
|RECORD=41|OwnerIndex=242|IndexInSheet=23|OwnerPartId=-1|Location.X=271|Location.Y=1039|Color=8388608|FontID=1|IsHidden=T|Text=1206|Name=Case Code (Imperial)
|RECORD=41|OwnerIndex=242|IndexInSheet=24|OwnerPartId=-1|Location.X=271|Location.Y=1039|Color=8388608|FontID=1|IsHidden=T|Text=Thick Film|Name=Type (Resistor)
|RECORD=41|OwnerIndex=242|IndexInSheet=25|OwnerPartId=-1|Location.X=271|Location.Y=1039|Color=8388608|FontID=1|IsHidden=T|Text=true|Name=RoHSCompliant
|RECORD=41|OwnerIndex=242|IndexInSheet=26|OwnerPartId=-1|Location.X=271|Location.Y=1039|Color=8388608|FontID=1|IsHidden=T|Text=5%|Name=Tolerance
|RECORD=41|OwnerIndex=242|IndexInSheet=27|OwnerPartId=-1|Location.X=271|Location.Y=1039|Color=8388608|FontID=1|IsHidden=T|Text=Datasheet|Name=ComponentLink2Description
|RECORD=41|OwnerIndex=242|IndexInSheet=28|OwnerPartId=-1|Location.X=271|Location.Y=1039|Color=8388608|FontID=1|IsHidden=T|Text=2-Pin Surface Mount Device, Body 1.6 x 0.85 mm|Name=PackageDescription
|RECORD=41|OwnerIndex=242|IndexInSheet=29|OwnerPartId=-1|Location.X=271|Location.Y=1039|Color=8388608|FontID=7|IsHidden=T|Text=http://www.panasonic.com/|Name=ComponentLink1URL
|RECORD=41|OwnerIndex=242|IndexInSheet=30|OwnerPartId=-1|Location.X=271|Location.Y=1039|Color=8388608|FontID=1|IsHidden=T|Text=250 mW|Name=Power Rating
|RECORD=34|OwnerIndex=242|IndexInSheet=-1|OwnerPartId=-1|Location.X=277|Location.Y=1018|Color=8388608|FontID=1|Text=R14|Name=Designator|ReadOnlyState=1
|RECORD=41|OwnerIndex=242|IndexInSheet=-1|OwnerPartId=-1|Location.X=277|Location.Y=1008|Color=8388608|FontID=1|Text=4.7K|Name=Comment
|RECORD=44|OwnerIndex=242
|RECORD=45|OwnerIndex=278|IndexInSheet=-1|Description=Chip Resistor, 2-Leads, Body 1.75x0.95mm, IPC Medium Density|UseComponentLibrary=T|ModelName=RESC1608X55X30NL15T15|ModelType=PCBLIB|DatafileCount=1|ModelDatafileEntity0=RESC1608X55X30NL15T15|ModelDatafileKind0=PCBLib|IsCurrent=T|DatalinksLocked=T|DatabaseDatalinksLocked=T
|RECORD=46|OwnerIndex=279
|RECORD=48|OwnerIndex=279
|RECORD=41|OwnerIndex=281|IndexInSheet=-1|OwnerPartId=-1|Color=8388608|FontID=1|IsHidden=T|Text=2D|Name=Available Preview Images
|RECORD=45|OwnerIndex=278|IndexInSheet=-1|Description=Chip Resistor, 2-Leads, Body 1.75x0.95mm, IPC Low Density|UseComponentLibrary=T|ModelName=RESC1608X55X30ML15T15|ModelType=PCBLIB|DatafileCount=1|ModelDatafileEntity0=RESC1608X55X30ML15T15|ModelDatafileKind0=PCBLib|DatalinksLocked=T|DatabaseDatalinksLocked=T
|RECORD=46|OwnerIndex=283
|RECORD=48|OwnerIndex=283
|RECORD=41|OwnerIndex=285|IndexInSheet=-1|OwnerPartId=-1|Color=8388608|FontID=1|IsHidden=T|Text=2D|Name=Available Preview Images
|RECORD=45|OwnerIndex=278|IndexInSheet=-1|Description=Chip Resistor, 2-Leads, Body 1.75x0.95mm, IPC High Density|UseComponentLibrary=T|ModelName=RESC1608X55X30LL15T15|ModelType=PCBLIB|DatafileCount=1|ModelDatafileEntity0=RESC1608X55X30LL15T15|ModelDatafileKind0=PCBLib|DatalinksLocked=T|DatabaseDatalinksLocked=T
|RECORD=46|OwnerIndex=287
|RECORD=48|OwnerIndex=287
|RECORD=41|OwnerIndex=289|IndexInSheet=-1|OwnerPartId=-1|Color=8388608|FontID=1|IsHidden=T|Text=2D|Name=Available Preview Images
|RECORD=1|LibReference=RES-2|ComponentDescription=Precision Thick Film Chip Resistor, 4.7 KOhm, +/- 1%, -55 to 155 degC, 0603 (1608 Metric), RoHS, Tape and Reel ERJ-3EKF4701V|PartCount=2|DisplayModeCount=1|IndexInSheet=42|OwnerPartId=-1|Location.X=304|Location.Y=1007|Orientation=1|CurrentPartId=1|LibraryPath=*|SourceLibraryName=Altium Content Vault|TargetFileName=*|AreaColor=11599871|Color=128|PartIDLocked=T|DesignItemId=CMP-1012-00586-3|AllPinCount=2
|RECORD=2|OwnerIndex=291|OwnerPartId=1|FormalType=1|Electrical=4|PinConglomerate=33|PinLength=10|Location.X=304|Location.Y=1027|Name=2|Designator=2|PinPropagationDelay=0.000000E+000
|RECORD=2|OwnerIndex=291|OwnerPartId=1|FormalType=1|Electrical=4|PinConglomerate=35|PinLength=10|Location.X=304|Location.Y=1007|Name=1|Designator=1|PinPropagationDelay=0.000000E+000
|RECORD=6|OwnerIndex=291|IsNotAccesible=T|IndexInSheet=2|OwnerPartId=1|LineWidth=1|Color=16711680|LocationCount=10|X1=304|Y1=1027|X2=304|Y2=1023|X3=306|Y3=1022|X4=302|Y4=1020|X5=306|Y5=1018|X6=302|Y6=1016|X7=306|Y7=1014|X8=302|Y8=1012|X9=304|Y9=1011|X10=304|Y10=1007
|RECORD=41|OwnerIndex=291|IndexInSheet=3|OwnerPartId=-1|Location.X=301|Location.Y=1039|Color=8388608|FontID=1|IsHidden=T|Text=220 Ohm|Name=Resistance
|RECORD=41|OwnerIndex=291|IndexInSheet=4|OwnerPartId=-1|Location.X=301|Location.Y=1039|Color=8388608|FontID=1|IsHidden=T|Text=0603|Name=PackageReference
|RECORD=41|OwnerIndex=291|IndexInSheet=5|OwnerPartId=-1|Location.X=301|Location.Y=1039|Color=8388608|FontID=1|IsHidden=T|Text=50 V|Name=Voltage Rating
|RECORD=41|OwnerIndex=291|IndexInSheet=6|OwnerPartId=-1|Location.X=301|Location.Y=1039|Color=8388608|FontID=1|IsHidden=T|Text=125 degC|Name=Max Operating Temperature
|RECORD=41|OwnerIndex=291|IndexInSheet=7|OwnerPartId=-1|Location.X=301|Location.Y=1039|Color=8388608|FontID=1|IsHidden=T|Text=4|Name=Elements
|RECORD=41|OwnerIndex=291|IndexInSheet=8|OwnerPartId=-1|Location.X=301|Location.Y=1039|Color=8388608|FontID=1|IsHidden=T|Text=No SVHC|Name=REACH SVHC
|RECORD=41|OwnerIndex=291|IndexInSheet=9|OwnerPartId=-1|Location.X=301|Location.Y=1039|Color=8388608|FontID=1|IsHidden=T|Text=0.063 inch|Name=Width
|RECORD=41|OwnerIndex=291|IndexInSheet=10|OwnerPartId=-1|Location.X=301|Location.Y=1039|Color=8388608|FontID=1|IsHidden=T|Text=1205|Name=Case\Package
|RECORD=41|OwnerIndex=291|IndexInSheet=11|OwnerPartId=-1|Location.X=301|Location.Y=1039|Color=8388608|FontID=1|IsHidden=T|Text=0.126 inch|Name=Length
|RECORD=41|OwnerIndex=291|IndexInSheet=12|OwnerPartId=-1|Location.X=301|Location.Y=1039|Color=8388608|FontID=1|IsHidden=T|Text=0.024 inch|Name=Height
|RECORD=41|OwnerIndex=291|IndexInSheet=13|OwnerPartId=-1|Location.X=301|Location.Y=1039|Color=8388608|FontID=1|IsHidden=T|Text=Surface Mount|Name=Mount
|RECORD=41|OwnerIndex=291|IndexInSheet=14|OwnerPartId=-1|Location.X=301|Location.Y=1039|Color=8388608|FontID=1|IsHidden=T|Text=1|Name=Package Quantity
|RECORD=41|OwnerIndex=291|IndexInSheet=15|OwnerPartId=-1|Location.X=301|Location.Y=1039|Color=8388608|FontID=1|IsHidden=T|Text=Apr-15|Name=DatasheetVersion
|RECORD=41|OwnerIndex=291|IndexInSheet=16|OwnerPartId=-1|Location.X=301|Location.Y=1039|Color=8388608|FontID=1|IsHidden=T|Text=Manufacturer URL|Name=ComponentLink1Description
|RECORD=41|OwnerIndex=291|IndexInSheet=17|OwnerPartId=-1|Location.X=301|Location.Y=1039|Color=8388608|FontID=1|IsHidden=T|Text=-55 degC|Name=Min Operating Temperature
|RECORD=41|OwnerIndex=291|IndexInSheet=18|OwnerPartId=-1|Location.X=301|Location.Y=1039|Color=8388608|FontID=1|IsHidden=T|Text=Tape and Reel|Name=Packaging
|RECORD=41|OwnerIndex=291|IndexInSheet=19|OwnerPartId=-1|Location.X=301|Location.Y=1039|Color=8388608|FontID=1|IsHidden=T|Text=No|Name=Radiation Hardening
|RECORD=41|OwnerIndex=291|IndexInSheet=20|OwnerPartId=-1|Location.X=301|Location.Y=1039|Color=8388608|FontID=7|IsHidden=T|Text=http://industrial.panasonic.com/cdbs/www-data/pdf/RDA0000/AOA0000C86.pdf|Name=ComponentLink2URL
|RECORD=41|OwnerIndex=291|IndexInSheet=21|OwnerPartId=-1|Location.X=301|Location.Y=1039|Color=8388608|FontID=1|IsHidden=T|Text=3216|Name=Case Code (Metric)
|RECORD=41|OwnerIndex=291|IndexInSheet=22|OwnerPartId=-1|Location.X=301|Location.Y=1039|Color=8388608|FontID=1|IsHidden=T|Text=8|Name=Pins
|RECORD=41|OwnerIndex=291|IndexInSheet=23|OwnerPartId=-1|Location.X=301|Location.Y=1039|Color=8388608|FontID=1|IsHidden=T|Text=1206|Name=Case Code (Imperial)
|RECORD=41|OwnerIndex=291|IndexInSheet=24|OwnerPartId=-1|Location.X=301|Location.Y=1039|Color=8388608|FontID=1|IsHidden=T|Text=Thick Film|Name=Type (Resistor)
|RECORD=41|OwnerIndex=291|IndexInSheet=25|OwnerPartId=-1|Location.X=301|Location.Y=1039|Color=8388608|FontID=1|IsHidden=T|Text=true|Name=RoHSCompliant
|RECORD=41|OwnerIndex=291|IndexInSheet=26|OwnerPartId=-1|Location.X=301|Location.Y=1039|Color=8388608|FontID=1|IsHidden=T|Text=5%|Name=Tolerance
|RECORD=41|OwnerIndex=291|IndexInSheet=27|OwnerPartId=-1|Location.X=301|Location.Y=1039|Color=8388608|FontID=1|IsHidden=T|Text=Datasheet|Name=ComponentLink2Description
|RECORD=41|OwnerIndex=291|IndexInSheet=28|OwnerPartId=-1|Location.X=301|Location.Y=1039|Color=8388608|FontID=1|IsHidden=T|Text=2-Pin Surface Mount Device, Body 1.6 x 0.85 mm|Name=PackageDescription
|RECORD=41|OwnerIndex=291|IndexInSheet=29|OwnerPartId=-1|Location.X=301|Location.Y=1039|Color=8388608|FontID=7|IsHidden=T|Text=http://www.panasonic.com/|Name=ComponentLink1URL
|RECORD=41|OwnerIndex=291|IndexInSheet=30|OwnerPartId=-1|Location.X=301|Location.Y=1039|Color=8388608|FontID=1|IsHidden=T|Text=250 mW|Name=Power Rating
|RECORD=34|OwnerIndex=291|IndexInSheet=-1|OwnerPartId=-1|Location.X=307|Location.Y=1018|Color=8388608|FontID=1|Text=R15|Name=Designator|ReadOnlyState=1
|RECORD=41|OwnerIndex=291|IndexInSheet=-1|OwnerPartId=-1|Location.X=307|Location.Y=1008|Color=8388608|FontID=1|Text=4.7K|Name=Comment
|RECORD=44|OwnerIndex=291
|RECORD=45|OwnerIndex=327|IndexInSheet=-1|Description=Chip Resistor, 2-Leads, Body 1.75x0.95mm, IPC Medium Density|UseComponentLibrary=T|ModelName=RESC1608X55X30NL15T15|ModelType=PCBLIB|DatafileCount=1|ModelDatafileEntity0=RESC1608X55X30NL15T15|ModelDatafileKind0=PCBLib|IsCurrent=T|DatalinksLocked=T|DatabaseDatalinksLocked=T
|RECORD=46|OwnerIndex=328
|RECORD=48|OwnerIndex=328
|RECORD=41|OwnerIndex=330|IndexInSheet=-1|OwnerPartId=-1|Color=8388608|FontID=1|IsHidden=T|Text=2D|Name=Available Preview Images
|RECORD=45|OwnerIndex=327|IndexInSheet=-1|Description=Chip Resistor, 2-Leads, Body 1.75x0.95mm, IPC Low Density|UseComponentLibrary=T|ModelName=RESC1608X55X30ML15T15|ModelType=PCBLIB|DatafileCount=1|ModelDatafileEntity0=RESC1608X55X30ML15T15|ModelDatafileKind0=PCBLib|DatalinksLocked=T|DatabaseDatalinksLocked=T
|RECORD=46|OwnerIndex=332
|RECORD=48|OwnerIndex=332
|RECORD=41|OwnerIndex=334|IndexInSheet=-1|OwnerPartId=-1|Color=8388608|FontID=1|IsHidden=T|Text=2D|Name=Available Preview Images
|RECORD=45|OwnerIndex=327|IndexInSheet=-1|Description=Chip Resistor, 2-Leads, Body 1.75x0.95mm, IPC High Density|UseComponentLibrary=T|ModelName=RESC1608X55X30LL15T15|ModelType=PCBLIB|DatafileCount=1|ModelDatafileEntity0=RESC1608X55X30LL15T15|ModelDatafileKind0=PCBLib|DatalinksLocked=T|DatabaseDatalinksLocked=T
|RECORD=46|OwnerIndex=336
|RECORD=48|OwnerIndex=336
|RECORD=41|OwnerIndex=338|IndexInSheet=-1|OwnerPartId=-1|Color=8388608|FontID=1|IsHidden=T|Text=2D|Name=Available Preview Images
|RECORD=17|IndexInSheet=43|OwnerPartId=-1|ShowNetName=T|Location.X=274|Location.Y=1037|Orientation=1|Color=128|FontID=1|Text=+3.3V
|RECORD=17|IndexInSheet=44|OwnerPartId=-1|ShowNetName=T|Location.X=304|Location.Y=1037|Orientation=1|Color=128|FontID=1|Text=+3.3V
|RECORD=17|IndexInSheet=45|OwnerPartId=-1|ShowNetName=T|Location.X=264|Location.Y=892|Orientation=2|Color=255|FontID=1|Text=ANT1_IN|IsCrossSheetConnector=T
|RECORD=41|OwnerIndex=342|OwnerPartId=-1|Location.X=211|Location.X_Frac=1146|Location.Y=892|Orientation=2|Justification=3|Color=8388608|FontID=1|Text=FPGA[4A]|Name=CrossRef|ReadOnlyState=3
|RECORD=1|LibReference=CAP|ComponentDescription=C0603X104K5RACAUTO|PartCount=2|DisplayModeCount=2|IndexInSheet=46|OwnerPartId=-1|Location.X=344|Location.Y=847|Orientation=3|CurrentPartId=1|SourceLibraryName=Altium Content Vault|TargetFileName=*|AreaColor=11599871|Color=128|PartIDLocked=F|DesignItemId=CMP-2006-00003-1|AllPinCount=2
|RECORD=2|OwnerIndex=344|OwnerPartId=1|OwnerPartDisplayMode=1|FormalType=1|Electrical=4|PinConglomerate=33|PinLength=10|Location.X=334|Location.Y=847|Name=1|Designator=1|PinPropagationDelay=0.000000E+000
|RECORD=2|OwnerIndex=344|OwnerPartId=1|OwnerPartDisplayMode=1|FormalType=1|Electrical=4|PinConglomerate=35|PinLength=10|Location.X=334|Location.Y=837|Name=2|Designator=2|PinPropagationDelay=0.000000E+000
|RECORD=13|OwnerIndex=344|IsNotAccesible=T|IndexInSheet=2|OwnerPartId=1|OwnerPartDisplayMode=1|Location.X=326|Location.Y=847|Corner.X=342|Corner.Y=847|LineWidth=1|Color=16711680
|RECORD=13|OwnerIndex=344|IsNotAccesible=T|IndexInSheet=3|OwnerPartId=1|OwnerPartDisplayMode=1|Location.X=334|Location.Y=843|Corner.X=334|Corner.Y=837|LineWidth=1|Color=16711680
|RECORD=12|OwnerIndex=344|IsNotAccesible=T|IndexInSheet=4|OwnerPartId=1|OwnerPartDisplayMode=1|Location.X=334|Location.Y=827|Radius=16|LineWidth=1|StartAngle=61.000|EndAngle=90.000|Color=16711680
|RECORD=12|OwnerIndex=344|IsNotAccesible=T|IndexInSheet=5|OwnerPartId=1|OwnerPartDisplayMode=1|Location.X=334|Location.Y=827|Radius=16|LineWidth=1|StartAngle=90.000|EndAngle=119.000|Color=16711680
|RECORD=2|OwnerIndex=344|OwnerPartId=1|FormalType=1|Electrical=4|PinConglomerate=33|PinLength=10|Location.X=334|Location.Y=847|Name=1|Designator=1|PinPropagationDelay=0.000000E+000
|RECORD=2|OwnerIndex=344|OwnerPartId=1|FormalType=1|Electrical=4|PinConglomerate=35|PinLength=10|Location.X=334|Location.Y=837|Name=2|Designator=2|PinPropagationDelay=0.000000E+000
|RECORD=13|OwnerIndex=344|IsNotAccesible=T|IndexInSheet=8|OwnerPartId=1|Location.X=342|Location.Y=840|Corner.X=326|Corner.Y=840|LineWidth=1|Color=16711680
|RECORD=13|OwnerIndex=344|IsNotAccesible=T|IndexInSheet=9|OwnerPartId=1|Location.X=326|Location.Y=844|Corner.X=342|Corner.Y=844|LineWidth=1|Color=16711680
|RECORD=6|OwnerIndex=344|IsNotAccesible=T|IndexInSheet=10|OwnerPartId=1|LineWidth=1|Color=16711680|LocationCount=2|X1=334|Y1=847|X2=334|Y2=844
|RECORD=6|OwnerIndex=344|IsNotAccesible=T|IndexInSheet=11|OwnerPartId=1|LineWidth=1|Color=16711680|LocationCount=2|X1=334|Y1=837|X2=334|Y2=840
|RECORD=41|OwnerIndex=344|IndexInSheet=12|OwnerPartId=-1|Location.X=325|Location.Y=859|Color=8388608|FontID=1|IsHidden=T|Text=Kemet|Name=Manufacturer
|RECORD=41|OwnerIndex=344|IndexInSheet=13|OwnerPartId=-1|Location.X=325|Location.Y=859|Color=8388608|FontID=1|IsHidden=T|Text=C0603X104K5RACAUTO|Name=Part Number
|RECORD=34|OwnerIndex=344|IndexInSheet=-1|OwnerPartId=-1|Location.X=343|Location.Y=834|Color=8388608|FontID=1|Text=C26|Name=Designator|ReadOnlyState=1
|RECORD=41|OwnerIndex=344|IndexInSheet=-1|OwnerPartId=-1|Location.X=343|Location.Y=820|Color=8388608|FontID=1|Text=0.1uF|Name=Comment
|RECORD=44|OwnerIndex=344
|RECORD=45|OwnerIndex=365|IndexInSheet=-1|Description=Chip Capacitor, 2-Leads, Body 1.60x0.80mm, IPC Low Density|UseComponentLibrary=T|ModelName=CAPC1608X87X45ML20T05|ModelType=PCBLIB|DatafileCount=1|ModelDatafileEntity0=CAPC1608X87X45ML20T05|ModelDatafileKind0=PCBLib|IsCurrent=T|DatalinksLocked=T|DatabaseDatalinksLocked=T
|RECORD=46|OwnerIndex=366
|RECORD=48|OwnerIndex=366
|RECORD=41|OwnerIndex=368|IndexInSheet=-1|OwnerPartId=-1|Color=8388608|FontID=1|Text=2D|Name=Available Preview Images
|RECORD=45|OwnerIndex=365|IndexInSheet=-1|Description=Chip Capacitor, 2-Leads, Body 1.60x0.80mm, IPC High Density|UseComponentLibrary=T|ModelName=CAPC1608X87X45LL20T05|ModelType=PCBLIB|DatafileCount=1|ModelDatafileEntity0=CAPC1608X87X45LL20T05|ModelDatafileKind0=PCBLib|DatalinksLocked=T|DatabaseDatalinksLocked=T
|RECORD=46|OwnerIndex=370
|RECORD=48|OwnerIndex=370
|RECORD=41|OwnerIndex=372|IndexInSheet=-1|OwnerPartId=-1|Color=8388608|FontID=1|Text=2D|Name=Available Preview Images
|RECORD=45|OwnerIndex=365|IndexInSheet=-1|Description=Chip Capacitor, 2-Leads, Body 1.60x0.80mm, IPC Medium Density|UseComponentLibrary=T|ModelName=CAPC1608X87X45NL20T05|ModelType=PCBLIB|DatafileCount=1|ModelDatafileEntity0=CAPC1608X87X45NL20T05|ModelDatafileKind0=PCBLib|DatalinksLocked=T|DatabaseDatalinksLocked=T
|RECORD=46|OwnerIndex=374
|RECORD=48|OwnerIndex=374
|RECORD=41|OwnerIndex=376|IndexInSheet=-1|OwnerPartId=-1|Color=8388608|FontID=1|Text=2D|Name=Available Preview Images
|RECORD=17|IndexInSheet=47|OwnerPartId=-1|Style=4|ShowNetName=T|Location.X=384|Location.Y=817|Orientation=3|Color=128|FontID=1|Text=GND
|RECORD=17|IndexInSheet=48|OwnerPartId=-1|Style=4|ShowNetName=T|Location.X=334|Location.Y=817|Orientation=3|Color=128|FontID=1|Text=GND
|RECORD=17|IndexInSheet=49|OwnerPartId=-1|ShowNetName=T|Location.X=334|Location.Y=1037|Orientation=1|Color=128|FontID=1|Text=+3.3V
|RECORD=1|LibReference=WE-TVS-HS-4|ComponentDescription=TVS Diode WE-TVS-HS, VRWM=3.3V|PartCount=2|DisplayModeCount=1|IndexInSheet=50|OwnerPartId=-1|Location.X=574|Location.Y=757|Orientation=1|CurrentPartId=1|LibraryPath=*|SourceLibraryName=Altium Content Vault|TargetFileName=*|AreaColor=11599871|Color=128|PartIDLocked=F|DesignItemId=CMP-1486-00002-1|AllPinCount=4
|RECORD=14|OwnerIndex=381|IsNotAccesible=T|OwnerPartId=1|Location.X=568|Location.Y=734|Corner.X=608|Corner.Y=772|AreaColor=11599871|IsSolid=T|Transparent=T
|RECORD=6|OwnerIndex=381|IsNotAccesible=T|IndexInSheet=1|OwnerPartId=1|LineWidth=1|Color=16711680|LocationCount=4|X1=578|X1_Frac=10000|Y1=758|Y1_Frac=40000|X2=576|X2_Frac=10000|Y2=756|Y2_Frac=40000|X3=572|X3_Frac=10000|Y3=756|Y3_Frac=40000|X4=570|X4_Frac=10000|Y4=754|Y4_Frac=40000
|RECORD=7|OwnerIndex=381|IsNotAccesible=T|IndexInSheet=2|OwnerPartId=1|LineWidth=1|Color=16711680|AreaColor=16711680|IsSolid=T|LocationCount=3|X1=578|X1_Frac=90000|Y1=750|Y1_Frac=50000|X2=573|X2_Frac=90000|Y2=755|Y2_Frac=50000|X3=568|X3_Frac=90000|Y3=750|Y3_Frac=50000
|RECORD=12|OwnerIndex=381|IsNotAccesible=T|IndexInSheet=3|OwnerPartId=1|Location.X=585|Location.Y=755|Radius_Frac=63392|LineWidth=1|StartAngle=57.394|EndAngle=30.947
|RECORD=6|OwnerIndex=381|IsNotAccesible=T|IndexInSheet=4|OwnerPartId=1|LineWidth=1|LocationCount=2|X1=594|Y1=755|X2=585|Y2=755
|RECORD=7|OwnerIndex=381|IsNotAccesible=T|IndexInSheet=5|OwnerPartId=1|LineWidth=1|Color=16711680|AreaColor=16711680|LocationCount=3|X1=589|X1_Frac=90000|Y1=742|Y1_Frac=50000|X2=584|X2_Frac=90000|Y2=747|Y2_Frac=50000|X3=579|X3_Frac=90000|Y3=742|Y3_Frac=50000
|RECORD=6|OwnerIndex=381|IsNotAccesible=T|IndexInSheet=6|OwnerPartId=1|LineWidth=1|Color=16711680|LocationCount=2|X1=581|Y1=748|X2=588|X2_Frac=87402|Y2=748
|RECORD=7|OwnerIndex=381|IsNotAccesible=T|IndexInSheet=7|OwnerPartId=1|LineWidth=1|Color=16711680|AreaColor=16711680|LocationCount=3|X1=589|X1_Frac=90000|Y1=758|Y1_Frac=50000|X2=584|X2_Frac=90000|Y2=763|Y2_Frac=50000|X3=579|X3_Frac=90000|Y3=758|Y3_Frac=50000
|RECORD=6|OwnerIndex=381|IsNotAccesible=T|IndexInSheet=8|OwnerPartId=1|LineWidth=1|Color=16711680|LocationCount=2|X1=581|Y1=764|X2=588|X2_Frac=87402|Y2=764
|RECORD=6|OwnerIndex=381|IsNotAccesible=T|IndexInSheet=9|OwnerPartId=1|LineWidth=1|LocationCount=2|X1=585|Y1=748|X2=585|Y2=758
|RECORD=6|OwnerIndex=381|IsNotAccesible=T|IndexInSheet=10|OwnerPartId=1|LineWidth=1|LocationCount=2|X1=585|Y1=764|X2=585|Y2=770
|RECORD=6|OwnerIndex=381|IsNotAccesible=T|IndexInSheet=11|OwnerPartId=1|LineWidth=1|LocationCount=2|X1=574|Y1=757|X2=574|Y2=770
|RECORD=6|OwnerIndex=381|IsNotAccesible=T|IndexInSheet=12|OwnerPartId=1|LineWidth=1|LocationCount=2|X1=574|Y1=736|X2=574|Y2=750
|RECORD=6|OwnerIndex=381|IsNotAccesible=T|IndexInSheet=13|OwnerPartId=1|LineWidth=1|LocationCount=2|X1=585|Y1=736|X2=585|Y2=742
|RECORD=6|OwnerIndex=381|IsNotAccesible=T|IndexInSheet=14|OwnerPartId=1|LineWidth=1|LocationCount=2|X1=574|Y1=736|X2=602|Y2=736
|RECORD=6|OwnerIndex=381|IsNotAccesible=T|IndexInSheet=15|OwnerPartId=1|LineWidth=1|LocationCount=2|X1=574|Y1=770|X2=602|Y2=770
|RECORD=6|OwnerIndex=381|IsNotAccesible=T|IndexInSheet=16|OwnerPartId=1|LineWidth=1|LocationCount=2|X1=594|Y1=751|X2=594|Y2=737
|RECORD=2|OwnerIndex=381|OwnerPartId=1|FormalType=1|Electrical=4|PinConglomerate=51|PinLength=10|Location.X=574|Location.Y=737|Name=GND|Designator=1|PinPropagationDelay=0.000000E+000
|RECORD=2|OwnerIndex=381|OwnerPartId=1|FormalType=1|Electrical=4|PinConglomerate=51|PinLength=10|Location.X=594|Location.Y=737|Name=I/O1|Designator=2|PinPropagationDelay=0.000000E+000
|RECORD=2|OwnerIndex=381|OwnerPartId=1|FormalType=1|Electrical=4|PinConglomerate=49|PinLength=10|Location.X=594|Location.Y=767|Name=I/O2|Designator=3|PinPropagationDelay=0.000000E+000
|RECORD=2|OwnerIndex=381|OwnerPartId=1|FormalType=1|Electrical=4|PinConglomerate=49|PinLength=10|Location.X=574|Location.Y=767|Name=VDD|Designator=4|PinPropagationDelay=0.000000E+000
|RECORD=12|OwnerIndex=381|IsNotAccesible=T|IndexInSheet=21|OwnerPartId=1|Location.X=574|Location.Y=770|Radius_Frac=63392|LineWidth=1|StartAngle=57.394|EndAngle=30.947
|RECORD=12|OwnerIndex=381|IsNotAccesible=T|IndexInSheet=22|OwnerPartId=1|Location.X=574|Location.Y=736|Radius_Frac=63392|LineWidth=1|StartAngle=57.394|EndAngle=30.947
|RECORD=12|OwnerIndex=381|IsNotAccesible=T|IndexInSheet=23|OwnerPartId=1|Location.X=602|Location.Y=751|Radius_Frac=63392|LineWidth=1|StartAngle=57.394|EndAngle=30.947
|RECORD=6|OwnerIndex=381|IsNotAccesible=T|IndexInSheet=24|OwnerPartId=1|LineWidth=1|LocationCount=2|X1=594|Y1=751|X2=602|Y2=751
|RECORD=7|OwnerIndex=381|IsNotAccesible=T|IndexInSheet=25|OwnerPartId=1|LineWidth=1|Color=16711680|AreaColor=16711680|LocationCount=3|X1=606|X1_Frac=90000|Y1=742|Y1_Frac=50000|X2=601|X2_Frac=90000|Y2=747|Y2_Frac=50000|X3=596|X3_Frac=90000|Y3=742|Y3_Frac=50000
|RECORD=6|OwnerIndex=381|IsNotAccesible=T|IndexInSheet=26|OwnerPartId=1|LineWidth=1|Color=16711680|LocationCount=2|X1=598|Y1=748|X2=605|X2_Frac=87402|Y2=748
|RECORD=7|OwnerIndex=381|IsNotAccesible=T|IndexInSheet=27|OwnerPartId=1|LineWidth=1|Color=16711680|AreaColor=16711680|LocationCount=3|X1=606|X1_Frac=90000|Y1=758|Y1_Frac=50000|X2=601|X2_Frac=90000|Y2=763|Y2_Frac=50000|X3=596|X3_Frac=90000|Y3=758|Y3_Frac=50000
|RECORD=6|OwnerIndex=381|IsNotAccesible=T|IndexInSheet=28|OwnerPartId=1|LineWidth=1|Color=16711680|LocationCount=2|X1=598|Y1=764|X2=605|X2_Frac=87402|Y2=764
|RECORD=6|OwnerIndex=381|IsNotAccesible=T|IndexInSheet=29|OwnerPartId=1|LineWidth=1|LocationCount=2|X1=602|Y1=748|X2=602|Y2=758
|RECORD=6|OwnerIndex=381|IsNotAccesible=T|IndexInSheet=30|OwnerPartId=1|LineWidth=1|LocationCount=2|X1=602|Y1=764|X2=602|Y2=770
|RECORD=6|OwnerIndex=381|IsNotAccesible=T|IndexInSheet=31|OwnerPartId=1|LineWidth=1|LocationCount=2|X1=602|Y1=736|X2=602|Y2=742
|RECORD=12|OwnerIndex=381|IsNotAccesible=T|IndexInSheet=32|OwnerPartId=1|Location.X=585|Location.Y=770|Radius_Frac=63392|LineWidth=1|StartAngle=57.394|EndAngle=30.947
|RECORD=12|OwnerIndex=381|IsNotAccesible=T|IndexInSheet=33|OwnerPartId=1|Location.X=585|Location.Y=736|Radius_Frac=63392|LineWidth=1|StartAngle=57.394|EndAngle=30.947
|RECORD=6|OwnerIndex=381|IsNotAccesible=T|IndexInSheet=34|OwnerPartId=1|LineWidth=1|LocationCount=2|X1=594|Y1=755|X2=594|Y2=772
|RECORD=41|OwnerIndex=381|IndexInSheet=35|OwnerPartId=-1|Location.X=567|Location.X_Frac=90000|Location.Y=779|Color=8388608|FontID=1|IsHidden=T|Text=8240136|Name=PartNumber
|RECORD=41|OwnerIndex=381|IndexInSheet=36|OwnerPartId=-1|Location.X=567|Location.X_Frac=90000|Location.Y=779|Color=8388608|FontID=1|IsHidden=T|Text=Manufacturer URL|Name=ComponentLink1Description
|RECORD=41|OwnerIndex=381|IndexInSheet=37|OwnerPartId=-1|Location.X=567|Location.X_Frac=90000|Location.Y=779|Color=8388608|FontID=1|IsHidden=T|Text=Wuerth Elektronik|Name=Manufacturer
|RECORD=41|OwnerIndex=381|IndexInSheet=38|OwnerPartId=-1|Location.X=567|Location.X_Frac=90000|Location.Y=779|Color=8388608|FontID=1|IsHidden=T|Text=SOT143-4L|Name=PackageReference
|RECORD=41|OwnerIndex=381|IndexInSheet=39|OwnerPartId=-1|Location.X=567|Location.X_Frac=90000|Location.Y=779|Color=8388608|FontID=7|IsHidden=T|Text=http://www.we-online.com|Name=ComponentLink1URL
|RECORD=41|OwnerIndex=381|IndexInSheet=40|OwnerPartId=-1|Location.X=567|Location.X_Frac=90000|Location.Y=779|Color=8388608|FontID=1|IsHidden=T|Text=3.3V|Name=Reverse Stand Off Voltage
|RECORD=41|OwnerIndex=381|IndexInSheet=41|OwnerPartId=-1|Location.X=567|Location.X_Frac=90000|Location.Y=779|Color=8388608|FontID=1|IsHidden=T|Text=Datasheet|Name=ComponentLink2Description
|RECORD=41|OwnerIndex=381|IndexInSheet=42|OwnerPartId=-1|Location.X=567|Location.X_Frac=90000|Location.Y=779|Color=8388608|FontID=7|IsHidden=T|Text=http://katalog.we-online.de/kataloge/eisos/media/pdf/8240136.pdf|Name=ComponentLink2URL
|RECORD=34|OwnerIndex=381|IndexInSheet=-1|OwnerPartId=-1|Location.X=608|Location.Y=763|Color=8388608|FontID=1|Text=D1|Name=Designator|ReadOnlyState=1
|RECORD=41|OwnerIndex=381|IndexInSheet=-1|OwnerPartId=-1|Location.X=608|Location.Y=753|Color=8388608|FontID=1|Text=8240136|Name=Comment
|RECORD=44|OwnerIndex=381
|RECORD=45|OwnerIndex=431|IndexInSheet=-1|Description=SOT143-4L, 4-Leads, Body 2.95x2.4mm, Pitch 1.70/1.90mm|UseComponentLibrary=T|ModelName=SOT143-4L|ModelType=PCBLIB|DatafileCount=1|ModelDatafileEntity0=SOT143-4L|ModelDatafileKind0=PCBLib|IsCurrent=T|DatalinksLocked=T|DatabaseDatalinksLocked=T
|RECORD=46|OwnerIndex=432
|RECORD=48|OwnerIndex=432
|RECORD=41|OwnerIndex=434|IndexInSheet=-1|OwnerPartId=-1|Color=8388608|FontID=1|IsHidden=T|Text=2D|Name=Available Preview Images
|RECORD=1|LibReference=NC7WV125K8X|ComponentDescription=Integrated Circuit|PartCount=2|DisplayModeCount=1|IndexInSheet=51|OwnerPartId=-1|Location.X=1154|Location.Y=882|CurrentPartId=1|LibraryPath=*|SourceLibraryName=SamacSys.SchLib|TargetFileName=*|AreaColor=11599871|Color=128|PartIDLocked=T|DesignItemId=NC7WV125K8X|AllPinCount=8
|RECORD=41|OwnerIndex=436|OwnerPartId=-1|Location.X=1154|Location.Y=882|Color=8388608|FontID=7|IsHidden=T|Text=https://www.mouser.com/datasheet/2/308/NC7WV125-1301459.pdf|Name=Datasheet Link
|RECORD=41|OwnerIndex=436|IndexInSheet=1|OwnerPartId=-1|Location.X=1154|Location.Y=882|Color=8388608|FontID=1|IsHidden=T|Text=0.9mm|Name=Height
|RECORD=41|OwnerIndex=436|IndexInSheet=2|OwnerPartId=-1|Location.X=1154|Location.Y=882|Color=8388608|FontID=1|IsHidden=T|Text=ON Semiconductor|Name=Manufacturer_Name
|RECORD=41|OwnerIndex=436|IndexInSheet=3|OwnerPartId=-1|Location.X=1154|Location.Y=882|Color=8388608|FontID=1|IsHidden=T|Text=NC7WV125K8X|Name=Manufacturer_Part_Number
|RECORD=41|OwnerIndex=436|IndexInSheet=4|OwnerPartId=-1|Location.X=1154|Location.Y=882|Color=8388608|FontID=1|IsHidden=T|Text=512-NC7WV125K8X|Name=Mouser Part Number
|RECORD=41|OwnerIndex=436|IndexInSheet=5|OwnerPartId=-1|Location.X=1154|Location.Y=882|Color=8388608|FontID=7|IsHidden=T|Text=https://www.mouser.com/Search/Refine.aspx?Keyword=512-NC7WV125K8X|Name=Mouser Price/Stock
|RECORD=41|OwnerIndex=436|IndexInSheet=6|OwnerPartId=-1|Location.X=1154|Location.Y=882|Color=8388608|FontID=1|IsHidden=T|Text=NC7WV125K8X|Name=Arrow Part Number
|RECORD=41|OwnerIndex=436|IndexInSheet=7|OwnerPartId=-1|Location.X=1154|Location.Y=882|Color=8388608|FontID=7|IsHidden=T|Text=https://www.arrow.com/en/products/nc7wv125k8x/on-semiconductor|Name=Arrow Price/Stock
|RECORD=14|OwnerIndex=436|IsNotAccesible=T|IndexInSheet=8|OwnerPartId=1|Location.X=1174|Location.Y=857|Corner.X=1244|Corner.Y=982|LineWidth=1|Color=128|AreaColor=11599871|IsSolid=T
|RECORD=2|OwnerIndex=436|OwnerPartId=1|FormalType=1|Electrical=4|PinConglomerate=58|PinLength=20|Location.X=1174|Location.Y=972|Designator=1|SwapIDPart=Ž&Ž||PinPropagationDelay=0.000000E+000
|RECORD=2|OwnerIndex=436|OwnerPartId=1|FormalType=1|Electrical=4|PinConglomerate=58|PinLength=20|Location.X=1174|Location.Y=947|Designator=2|SwapIDPart=Ž&Ž||PinPropagationDelay=0.000000E+000
|RECORD=2|OwnerIndex=436|OwnerPartId=1|FormalType=1|Electrical=4|PinConglomerate=58|PinLength=20|Location.X=1174|Location.Y=892|Designator=3|SwapIDPart=Ž&Ž||PinPropagationDelay=0.000000E+000
|RECORD=2|OwnerIndex=436|OwnerPartId=1|FormalType=1|Electrical=4|PinConglomerate=58|PinLength=20|Location.X=1174|Location.Y=862|Name=GND|Designator=4|SwapIDPart=Ž&Ž||PinPropagationDelay=0.000000E+000
|RECORD=2|OwnerIndex=436|OwnerPartId=1|FormalType=1|Electrical=4|PinConglomerate=58|PinLength=20|Location.X=1174|Location.Y=872|Name=VCC|Designator=8|SwapIDPart=Ž&Ž||PinPropagationDelay=0.000000E+000
|RECORD=2|OwnerIndex=436|OwnerPartId=1|FormalType=1|Electrical=4|PinConglomerate=58|PinLength=20|Location.X=1174|Location.Y=917|Designator=7|SwapIDPart=Ž&Ž||PinPropagationDelay=0.000000E+000
|RECORD=2|OwnerIndex=436|OwnerPartId=1|FormalType=1|Electrical=4|PinConglomerate=56|PinLength=20|Location.X=1244|Location.Y=947|Designator=6|SwapIDPart=Ž&Ž||PinPropagationDelay=0.000000E+000
|RECORD=2|OwnerIndex=436|OwnerPartId=1|FormalType=1|Electrical=4|PinConglomerate=56|PinLength=20|Location.X=1244|Location.Y=892|Designator=5|SwapIDPart=Ž&Ž||PinPropagationDelay=0.000000E+000
|RECORD=6|OwnerIndex=436|IsNotAccesible=T|IndexInSheet=17|OwnerPartId=1|LineWidth=1|Color=16711680|LocationCount=4|X1=1199|Y1=957|X2=1199|Y2=937|X3=1219|Y3=947|X4=1199|Y4=957
|RECORD=12|OwnerIndex=436|IsNotAccesible=T|IndexInSheet=18|OwnerPartId=1|Location.X=1209|Location.Y=954|Radius=1|Radius_Frac=79777|LineWidth=1|EndAngle=360.000|Color=16711680
|RECORD=6|OwnerIndex=436|IsNotAccesible=T|IndexInSheet=19|OwnerPartId=1|LineWidth=1|Color=16711680|LocationCount=4|X1=1219|Y1=902|X2=1219|Y2=882|X3=1199|Y3=892|X4=1219|Y4=902
|RECORD=12|OwnerIndex=436|IsNotAccesible=T|IndexInSheet=20|OwnerPartId=1|Location.X=1209|Location.Y=899|Radius=1|Radius_Frac=79777|LineWidth=1|EndAngle=360.000|Color=16711680
|RECORD=6|OwnerIndex=436|IsNotAccesible=T|IndexInSheet=21|OwnerPartId=1|LineWidth=1|Color=16711680|LocationCount=3|X1=1209|Y1=901|X2=1209|Y2=917|X3=1174|Y3=917
|RECORD=6|OwnerIndex=436|IsNotAccesible=T|IndexInSheet=22|OwnerPartId=1|LineWidth=1|Color=16711680|LocationCount=3|X1=1209|Y1=956|X2=1209|Y2=972|X3=1174|Y3=972
|RECORD=6|OwnerIndex=436|IsNotAccesible=T|IndexInSheet=23|OwnerPartId=1|LineWidth=1|Color=16711680|LocationCount=2|X1=1174|Y1=947|X2=1199|Y2=947
|RECORD=6|OwnerIndex=436|IsNotAccesible=T|IndexInSheet=24|OwnerPartId=1|LineWidth=1|Color=16711680|LocationCount=2|X1=1219|Y1=947|X2=1244|Y2=947
|RECORD=6|OwnerIndex=436|IsNotAccesible=T|IndexInSheet=25|OwnerPartId=1|LineWidth=1|Color=16711680|LocationCount=2|X1=1219|Y1=892|X2=1244|Y2=892
|RECORD=6|OwnerIndex=436|IsNotAccesible=T|IndexInSheet=26|OwnerPartId=1|LineWidth=1|Color=16711680|LocationCount=2|X1=1199|Y1=892|X2=1174|Y2=892
|RECORD=34|OwnerIndex=436|IndexInSheet=-1|OwnerPartId=-1|Location.X=1173|Location.Y=982|Color=8388608|FontID=1|Text=U11|Name=Designator|ReadOnlyState=1
|RECORD=41|OwnerIndex=436|IndexInSheet=-1|OwnerPartId=-1|Location.X=1173|Location.Y=847|Color=8388608|FontID=1|Text=NC7WV125K8X|Name=Comment
|RECORD=44|OwnerIndex=436
|RECORD=45|OwnerIndex=474|IndexInSheet=-1|ModelName=SOP50P310X90-8N|ModelType=PCBLIB|DatafileCount=1|ModelDatafile0=C:\Users\<user>\Documents\AltiumLL\SamacSys.PcbLib|ModelDatafileEntity0=SOP50P310X90-8N|ModelDatafileKind0=PCBLIB|IsCurrent=T
|RECORD=46|OwnerIndex=475
|RECORD=48|OwnerIndex=475
|RECORD=17|IndexInSheet=52|OwnerPartId=-1|Style=4|ShowNetName=T|Location.X=1464|Location.Y=817|Orientation=3|Color=128|FontID=1|Text=GND
|RECORD=1|LibReference=CN-1P-M-RF3|ComponentDescription=Ultra Miniature Coaxial Connector Jack, 60 V, 50 Ohm, -40 to 90 degC, RoHS, Tape and Reel|PartCount=2|DisplayModeCount=1|IndexInSheet=53|OwnerPartId=-1|Location.X=1394|Location.Y=967|CurrentPartId=1|LibraryPath=*|SourceLibraryName=Altium Content Vault|TargetFileName=*|AreaColor=11599871|Color=128|PartIDLocked=T|DesignItemId=CMP-2000-07505-1|AllPinCount=3
|RECORD=8|OwnerIndex=479|IsNotAccesible=T|OwnerPartId=1|Location.X=1414|Location.Y=947|Radius=20|SecondaryRadius=20|LineWidth=1|Color=16711680|AreaColor=16777215
|RECORD=8|OwnerIndex=479|IsNotAccesible=T|IndexInSheet=1|OwnerPartId=1|Location.X=1414|Location.Y=947|Radius=4|SecondaryRadius=4|LineWidth=1|Color=16711680|AreaColor=16777215
|RECORD=2|OwnerIndex=479|OwnerPartId=1|FormalType=1|Electrical=4|PinConglomerate=51|PinLength=10|Location.X=1404|Location.Y=927|Name=1|Designator=1|PinPropagationDelay=0.000000E+000
|RECORD=2|OwnerIndex=479|OwnerPartId=1|FormalType=1|Electrical=4|PinConglomerate=50|PinLength=10|Location.X=1394|Location.Y=947|Name=2|Designator=2|PinPropagationDelay=0.000000E+000
|RECORD=2|OwnerIndex=479|OwnerPartId=1|FormalType=1|Electrical=4|PinConglomerate=51|PinLength=10|Location.X=1424|Location.Y=927|Name=3|Designator=3|PinPropagationDelay=0.000000E+000
|RECORD=6|OwnerIndex=479|IsNotAccesible=T|IndexInSheet=5|OwnerPartId=1|LineWidth=1|Color=16711680|LocationCount=5|X1=1394|Y1=927|X2=1394|Y2=967|X3=1434|Y3=967|X4=1434|Y4=927|X5=1394|Y5=927
|RECORD=6|OwnerIndex=479|IsNotAccesible=T|IndexInSheet=6|OwnerPartId=1|LineWidth=1|Color=16711680|LocationCount=2|X1=1394|Y1=947|X2=1410|Y2=947
|RECORD=41|OwnerIndex=479|IndexInSheet=7|OwnerPartId=-1|Location.X=1382|Location.Y=968|Color=8388608|FontID=1|IsHidden=T|Text=Straight|Name=Orientation
|RECORD=41|OwnerIndex=479|IndexInSheet=8|OwnerPartId=-1|Location.X=1382|Location.Y=968|Color=8388608|FontID=1|IsHidden=T|Text=Female|Name=Gender
|RECORD=41|OwnerIndex=479|IndexInSheet=9|OwnerPartId=-1|Location.X=1382|Location.Y=968|Color=8388608|FontID=1|IsHidden=T|Text=Vertical|Name=PCB Mounting Orientation
|RECORD=41|OwnerIndex=479|IndexInSheet=10|OwnerPartId=-1|Location.X=1382|Location.Y=968|Color=8388608|FontID=1|IsHidden=T|Text=SurfaceMount|Name=Mount
|RECORD=41|OwnerIndex=479|IndexInSheet=11|OwnerPartId=-1|Location.X=1382|Location.Y=968|Color=8388608|FontID=1|IsHidden=T|Text=3mm|Name=Length
|RECORD=41|OwnerIndex=479|IndexInSheet=12|OwnerPartId=-1|Location.X=1382|Location.Y=968|Color=8388608|FontID=1|IsHidden=T|Text=TapeandReel|Name=Packaging
|RECORD=41|OwnerIndex=479|IndexInSheet=13|OwnerPartId=-1|Location.X=1382|Location.Y=968|Color=8388608|FontID=1|IsHidden=T|Text=Jack|Name=Connector Type
|RECORD=41|OwnerIndex=479|IndexInSheet=14|OwnerPartId=-1|Location.X=1382|Location.Y=968|Color=8388608|FontID=1|IsHidden=T|Text=LeadFree|Name=Lead Free
|RECORD=41|OwnerIndex=479|IndexInSheet=15|OwnerPartId=-1|Location.X=1382|Location.Y=968|Color=8388608|FontID=1|IsHidden=T|Text=1|Name=Package Quantity
|RECORD=41|OwnerIndex=479|IndexInSheet=16|OwnerPartId=-1|Location.X=1382|Location.Y=968|Color=8388608|FontID=1|IsHidden=T|Text=SMD/SMT|Name=Termination
|RECORD=41|OwnerIndex=479|IndexInSheet=17|OwnerPartId=-1|Location.X=1382|Location.Y=968|Color=8388608|FontID=1|IsHidden=T|Text=CopperAlloy|Name=Contact Material
|RECORD=41|OwnerIndex=479|IndexInSheet=18|OwnerPartId=-1|Location.X=1382|Location.Y=968|Color=8388608|FontID=1|IsHidden=T|Text=Pull|Name=Fastening Type
|RECORD=41|OwnerIndex=479|IndexInSheet=19|OwnerPartId=-1|Location.X=1382|Location.Y=968|Color=8388608|FontID=1|IsHidden=T|Text=true|Name=RoHSCompliant
|RECORD=41|OwnerIndex=479|IndexInSheet=20|OwnerPartId=-1|Location.X=1382|Location.Y=968|Color=8388608|FontID=1|IsHidden=T|Text=LiquidCrystalPolymer|Name=Body Material
|RECORD=41|OwnerIndex=479|IndexInSheet=21|OwnerPartId=-1|Location.X=1382|Location.Y=968|Color=8388608|FontID=1|IsHidden=T|Text=SMD/SMT|Name=Case\/Package
|RECORD=41|OwnerIndex=479|IndexInSheet=22|OwnerPartId=-1|Location.X=1382|Location.Y=968|Color=8388608|FontID=1|IsHidden=T|Text=90degC|Name=Max Operating Temperature
|RECORD=41|OwnerIndex=479|IndexInSheet=23|OwnerPartId=-1|Location.X=1382|Location.Y=968|Color=8388608|FontID=1|IsHidden=T|Text=50Ohm|Name=Impedance
|RECORD=41|OwnerIndex=479|IndexInSheet=24|OwnerPartId=-1|Location.X=1382|Location.Y=968|Color=8388608|FontID=7|IsHidden=T|Text=http://www.te.com/commerce/DocumentDelivery/DDEController?Action=srchrtrv&DocNm=1909763&DocType=Customer+Drawing&DocLang=English|Name=Datasheet URL
|RECORD=41|OwnerIndex=479|IndexInSheet=25|OwnerPartId=-1|Location.X=1382|Location.Y=968|Color=8388608|FontID=1|IsHidden=T|Text=Gold|Name=Contact Plating
|RECORD=41|OwnerIndex=479|IndexInSheet=26|OwnerPartId=-1|Location.X=1382|Location.Y=968|Color=8388608|FontID=1|IsHidden=T|Text=SurfaceMount|Name=Mounting Technology
|RECORD=41|OwnerIndex=479|IndexInSheet=27|OwnerPartId=-1|Location.X=1382|Location.Y=968|Color=8388608|FontID=1|IsHidden=T|Text=6GHz|Name=Max Frequency
|RECORD=41|OwnerIndex=479|IndexInSheet=28|OwnerPartId=-1|Location.X=1382|Location.Y=968|Color=8388608|FontID=1|IsHidden=T|Text=TECO-1909763-1|Name=Package Reference
|RECORD=41|OwnerIndex=479|IndexInSheet=29|OwnerPartId=-1|Location.X=1382|Location.Y=968|Color=8388608|FontID=1|IsHidden=T|Text=Thermoplastic|Name=Insulation Material
|RECORD=41|OwnerIndex=479|IndexInSheet=30|OwnerPartId=-1|Location.X=1382|Location.Y=968|Color=8388608|FontID=1|IsHidden=T|Text=-40degC|Name=Min Operating Temperature
|RECORD=41|OwnerIndex=479|IndexInSheet=31|OwnerPartId=-1|Location.X=1382|Location.Y=968|Color=8388608|FontID=7|IsHidden=T|Text=http://www.te.com/|Name=Manufacturer URL
|RECORD=41|OwnerIndex=479|IndexInSheet=32|OwnerPartId=-1|Location.X=1382|Location.Y=968|Color=8388608|FontID=1|IsHidden=T|Text=Gold|Name=Body Plating
|RECORD=41|OwnerIndex=479|IndexInSheet=33|OwnerPartId=-1|Location.X=1382|Location.Y=968|Color=8388608|FontID=1|IsHidden=T|Text=Polymer|Name=Dielectric Material
|RECORD=41|OwnerIndex=479|IndexInSheet=34|OwnerPartId=-1|Location.X=1382|Location.Y=968|Color=8388608|FontID=1|IsHidden=T|Text=TE Connectivity|Name=Manufacturer
|RECORD=41|OwnerIndex=479|IndexInSheet=35|OwnerPartId=-1|Location.X=1382|Location.Y=968|Color=8388608|FontID=1|IsHidden=T|Text=Compliant|Name=ELV
|RECORD=41|OwnerIndex=479|IndexInSheet=36|OwnerPartId=-1|Location.X=1382|Location.Y=968|Color=8388608|FontID=1|IsHidden=T|Text=Rev. B2, 11/2015|Name=Datasheet Version
|RECORD=41|OwnerIndex=479|IndexInSheet=37|OwnerPartId=-1|Location.X=1382|Location.Y=968|Color=8388608|FontID=1|IsHidden=T|Text=No|Name=Radiation Hardening
|RECORD=41|OwnerIndex=479|IndexInSheet=38|OwnerPartId=-1|Location.X=1382|Location.Y=968|Color=8388608|FontID=1|IsHidden=T|Text=3-Pin Surface Mount Device, Body 2.6 x 2.6 mm|Name=Package Description
|RECORD=41|OwnerIndex=479|IndexInSheet=39|OwnerPartId=-1|Location.X=1382|Location.Y=968|Color=8388608|FontID=1|IsHidden=T|Text=Beige|Name=Housing Colour
|RECORD=34|OwnerIndex=479|IndexInSheet=-1|OwnerPartId=-1|Location.X=1393|Location.Y=968|Color=8388608|FontID=1|Text=J3|Name=Designator|ReadOnlyState=1
|RECORD=41|OwnerIndex=479|IndexInSheet=-1|OwnerPartId=-1|Location.X=1444|Location.Y=927|Color=8388608|FontID=1|Text=1909763-1|Name=Comment
|RECORD=44|OwnerIndex=479
|RECORD=45|OwnerIndex=525|IndexInSheet=-1|Description=SMD, 3-Leads, Body 2.6x2.6mm, Height 1.25mm|UseComponentLibrary=T|ModelName=TECO-1909763-1_V|ModelType=PCBLIB|DatafileCount=1|ModelDatafileEntity0=TECO-1909763-1_V|ModelDatafileKind0=PCBLib|IsCurrent=T|DatalinksLocked=T|DatabaseDatalinksLocked=T
|RECORD=46|OwnerIndex=526
|RECORD=48|OwnerIndex=526
|RECORD=41|OwnerIndex=528|IndexInSheet=-1|OwnerPartId=-1|Color=8388608|FontID=1|Text=2D|Name=Available Preview Images
|RECORD=1|LibReference=CN-S-4F-RF5|ComponentDescription=Coaxial connector, 50 Ohm, -65 to 165 degC, 5-Pin THD, RoHS, Bulk|PartCount=2|DisplayModeCount=1|IndexInSheet=54|OwnerPartId=-1|Location.X=1394|Location.Y=887|CurrentPartId=1|LibraryPath=*|SourceLibraryName=Altium Content Vault|TargetFileName=*|AreaColor=11599871|Color=128|PartIDLocked=T|DesignItemId=CMP-2000-05705-1|AllPinCount=5
|RECORD=2|OwnerIndex=530|OwnerPartId=1|FormalType=1|Electrical=4|PinConglomerate=51|PinLength=10|Location.X=1434|Location.Y=847|Name=5|Designator=5|SwapIDPart=Ž&Ž1|PinPropagationDelay=0.000000E+000
|RECORD=8|OwnerIndex=530|IsNotAccesible=T|IndexInSheet=1|OwnerPartId=1|Location.X=1414|Location.Y=867|Radius=20|SecondaryRadius=20|LineWidth=1|Color=16711680|AreaColor=16777215
|RECORD=8|OwnerIndex=530|IsNotAccesible=T|IndexInSheet=2|OwnerPartId=1|Location.X=1414|Location.Y=867|Radius=4|SecondaryRadius=4|LineWidth=1|Color=16711680|AreaColor=16777215
|RECORD=2|OwnerIndex=530|OwnerPartId=1|FormalType=1|Electrical=4|PinConglomerate=50|PinLength=10|Location.X=1394|Location.Y=867|Name=1|Designator=1|PinPropagationDelay=0.000000E+000
|RECORD=2|OwnerIndex=530|OwnerPartId=1|FormalType=1|Electrical=4|PinConglomerate=51|PinLength=10|Location.X=1404|Location.Y=847|Name=2|Designator=2|PinPropagationDelay=0.000000E+000
|RECORD=2|OwnerIndex=530|OwnerPartId=1|FormalType=1|Electrical=4|PinConglomerate=51|PinLength=10|Location.X=1414|Location.Y=847|Name=3|Designator=3|PinPropagationDelay=0.000000E+000
|RECORD=2|OwnerIndex=530|OwnerPartId=1|FormalType=1|Electrical=4|PinConglomerate=51|PinLength=10|Location.X=1424|Location.Y=847|Name=4|Designator=4|PinPropagationDelay=0.000000E+000
|RECORD=6|OwnerIndex=530|IsNotAccesible=T|IndexInSheet=7|OwnerPartId=1|LineWidth=1|Color=16711680|LocationCount=5|X1=1394|Y1=847|X2=1394|Y2=887|X3=1434|Y3=887|X4=1434|Y4=847|X5=1394|Y5=847
|RECORD=6|OwnerIndex=530|IsNotAccesible=T|IndexInSheet=8|OwnerPartId=1|LineWidth=1|Color=16711680|LocationCount=2|X1=1394|Y1=867|X2=1410|Y2=867
|RECORD=41|OwnerIndex=530|IndexInSheet=9|OwnerPartId=-1|Location.X=1382|Location.Y=888|Color=8388608|FontID=1|IsHidden=T|Text=ThroughHole|Name=Mounting Technology
|RECORD=41|OwnerIndex=530|IndexInSheet=10|OwnerPartId=-1|Location.X=1382|Location.Y=888|Color=8388608|FontID=1|IsHidden=T|Text=ThroughHole,RightAngle|Name=Mounting Type
|RECORD=41|OwnerIndex=530|IndexInSheet=11|OwnerPartId=-1|Location.X=1382|Location.Y=888|Color=8388608|FontID=1|IsHidden=T|Text=-|Name=Cable Group
|RECORD=41|OwnerIndex=530|IndexInSheet=12|OwnerPartId=-1|Location.X=1382|Location.Y=888|Color=8388608|FontID=1|IsHidden=T|Text=901-143-6RFXMountingHole|Name=Catalog Drawings
|RECORD=41|OwnerIndex=530|IndexInSheet=13|OwnerPartId=-1|Location.X=1382|Location.Y=888|Color=8388608|FontID=1|IsHidden=T|Text=901-143-6RFX.igs|Name=3D Model
|RECORD=41|OwnerIndex=530|IndexInSheet=14|OwnerPartId=-1|Location.X=1382|Location.Y=888|Color=8388608|FontID=1|IsHidden=T|Text=-|Name=Series
|RECORD=41|OwnerIndex=530|IndexInSheet=15|OwnerPartId=-1|Location.X=1382|Location.Y=888|Color=8388608|FontID=1|IsHidden=T|Text=5-Pin Through Hole Device, Body 7 x 7 mm, Pitch 2.54 mm|Name=Package Description
|RECORD=41|OwnerIndex=530|IndexInSheet=16|OwnerPartId=-1|Location.X=1382|Location.Y=888|Color=8388608|FontID=1|IsHidden=T|Text=901-143-6RFX|Name=Package Reference
|RECORD=41|OwnerIndex=530|IndexInSheet=17|OwnerPartId=-1|Location.X=1382|Location.Y=888|Color=8388608|FontID=1|IsHidden=T|Text=Brass|Name=Body Material
|RECORD=41|OwnerIndex=530|IndexInSheet=18|OwnerPartId=-1|Location.X=1382|Location.Y=888|Color=8388608|FontID=1|IsHidden=T|Text=-|Name=Voltage Rating
|RECORD=41|OwnerIndex=530|IndexInSheet=19|OwnerPartId=-1|Location.X=1382|Location.Y=888|Color=8388608|FontID=1|IsHidden=T|Text=1|Name=Standard Package
|RECORD=41|OwnerIndex=530|IndexInSheet=20|OwnerPartId=-1|Location.X=1382|Location.Y=888|Color=8388608|FontID=1|IsHidden=T|Text=Jack,FemaleSocket|Name=Connector Type
|RECORD=41|OwnerIndex=530|IndexInSheet=21|OwnerPartId=-1|Location.X=1382|Location.Y=888|Color=8388608|FontID=1|IsHidden=T|Text=Threaded|Name=Fastening Type
|RECORD=41|OwnerIndex=530|IndexInSheet=22|OwnerPartId=-1|Location.X=1382|Location.Y=888|Color=8388608|FontID=1|IsHidden=T|Text=Gold|Name=Housing Color
|RECORD=41|OwnerIndex=530|IndexInSheet=23|OwnerPartId=-1|Location.X=1382|Location.Y=888|Color=8388608|FontID=1|IsHidden=T|Text=Solder|Name=Shield Termination
|RECORD=41|OwnerIndex=530|IndexInSheet=24|OwnerPartId=-1|Location.X=1382|Location.Y=888|Color=8388608|FontID=1|IsHidden=T|Text=901-143-6-RFX9011436RFXARFX1232|Name=Other Names
|RECORD=41|OwnerIndex=530|IndexInSheet=25|OwnerPartId=-1|Location.X=1382|Location.Y=888|Color=8388608|FontID=7|IsHidden=T|Text=http://www.amphenolrf.com/downloads/dl/file/id/2712/product/3102/901_143_6rfx_customer_drawing.pdf|Name=Datasheet URL
|RECORD=41|OwnerIndex=530|IndexInSheet=26|OwnerPartId=-1|Location.X=1382|Location.Y=888|Color=8388608|FontID=1|IsHidden=T|Text=CoaxialConnectors(RF)|Name=Family
|RECORD=41|OwnerIndex=530|IndexInSheet=27|OwnerPartId=-1|Location.X=1382|Location.Y=888|Color=8388608|FontID=1|IsHidden=T|Text=SMA,RFX|Name=Online Catalog
|RECORD=41|OwnerIndex=530|IndexInSheet=28|OwnerPartId=-1|Location.X=1382|Location.Y=888|Color=8388608|FontID=1|IsHidden=T|Text=18GHz|Name=Frequency - Max
|RECORD=41|OwnerIndex=530|IndexInSheet=29|OwnerPartId=-1|Location.X=1382|Location.Y=888|Color=8388608|FontID=1|IsHidden=T|Text=Solder|Name=Contact Termination
|RECORD=41|OwnerIndex=530|IndexInSheet=30|OwnerPartId=-1|Location.X=1382|Location.Y=888|Color=8388608|FontID=7|IsHidden=T|Text=http://www.amphenol.com/|Name=Manufacturer URL
|RECORD=41|OwnerIndex=530|IndexInSheet=31|OwnerPartId=-1|Location.X=1382|Location.Y=888|Color=8388608|FontID=1|IsHidden=T|Text=Amphenol|Name=Manufacturer
|RECORD=41|OwnerIndex=530|IndexInSheet=32|OwnerPartId=-1|Location.X=1382|Location.Y=888|Color=8388608|FontID=1|IsHidden=T|Text=-65°C~165°C|Name=Operating Temperature
|RECORD=41|OwnerIndex=530|IndexInSheet=33|OwnerPartId=-1|Location.X=1382|Location.Y=888|Color=8388608|FontID=1|IsHidden=T|Text=Connectors,Interconnects|Name=Category
|RECORD=41|OwnerIndex=530|IndexInSheet=34|OwnerPartId=-1|Location.X=1382|Location.Y=888|Color=8388608|FontID=1|IsHidden=T|Text=Bulk|Name=Packaging
|RECORD=41|OwnerIndex=530|IndexInSheet=35|OwnerPartId=-1|Location.X=1382|Location.Y=888|Color=8388608|FontID=1|IsHidden=T|Text=Gold|Name=Body Finish
|RECORD=41|OwnerIndex=530|IndexInSheet=36|OwnerPartId=-1|Location.X=1382|Location.Y=888|Color=8388608|FontID=1|IsHidden=T|Text=Polytetrafluoroethylene(PTFE)|Name=Dielectric Material
|RECORD=41|OwnerIndex=530|IndexInSheet=37|OwnerPartId=-1|Location.X=1382|Location.Y=888|Color=8388608|FontID=1|IsHidden=T|Text=BerylliumCopper|Name=Center Contact Material
|RECORD=41|OwnerIndex=530|IndexInSheet=38|OwnerPartId=-1|Location.X=1382|Location.Y=888|Color=8388608|FontID=1|IsHidden=T|Text=50Ohm|Name=Impedance
|RECORD=41|OwnerIndex=530|IndexInSheet=39|OwnerPartId=-1|Location.X=1382|Location.Y=888|Color=8388608|FontID=1|IsHidden=T|Text=-|Name=Features
|RECORD=41|OwnerIndex=530|IndexInSheet=40|OwnerPartId=-1|Location.X=1382|Location.Y=888|Color=8388608|FontID=1|IsHidden=T|Text=SMA|Name=Connector Style
|RECORD=41|OwnerIndex=530|IndexInSheet=41|OwnerPartId=-1|Location.X=1382|Location.Y=888|Color=8388608|FontID=1|IsHidden=T|Text=Gold|Name=Center Contact Plating
|RECORD=41|OwnerIndex=530|IndexInSheet=42|OwnerPartId=-1|Location.X=1382|Location.Y=888|Color=8388608|FontID=1|IsHidden=T|Text=Rev. C, 06/2010|Name=Datasheet Version
|RECORD=41|OwnerIndex=530|IndexInSheet=43|OwnerPartId=-1|Location.X=1382|Location.Y=888|Color=8388608|FontID=1|IsHidden=T|Text=-|Name=Ingress Protection
|RECORD=34|OwnerIndex=530|IndexInSheet=-1|OwnerPartId=-1|Location.X=1393|Location.Y=888|Color=8388608|FontID=1|Text=AN3|Name=Designator|ReadOnlyState=1
|RECORD=41|OwnerIndex=530|IndexInSheet=-1|OwnerPartId=-1|Location.X=1444|Location.Y=837|Color=8388608|FontID=1|Text=RF2-49B-T-00-50-G-HDW|Name=Comment
|RECORD=44|OwnerIndex=530
|RECORD=45|OwnerIndex=582|IndexInSheet=-1|Description=THD, 5-Leads, Body 7x7mm, Pitch 2.54mm|UseComponentLibrary=T|ModelName=AMPH-901-143-6RFX_V|ModelType=PCBLIB|DatafileCount=1|ModelDatafileEntity0=AMPH-901-143-6RFX_V|ModelDatafileKind0=PCBLib|IsCurrent=T|DatalinksLocked=T|DatabaseDatalinksLocked=T
|RECORD=46|OwnerIndex=583
|RECORD=48|OwnerIndex=583
|RECORD=41|OwnerIndex=585|IndexInSheet=-1|OwnerPartId=-1|Color=8388608|FontID=1|Text=2D|Name=Available Preview Images
|RECORD=17|IndexInSheet=55|OwnerPartId=-1|Style=4|ShowNetName=T|Location.X=1464|Location.Y=907|Orientation=3|Color=128|FontID=1|Text=GND
|RECORD=1|LibReference=RES-2|ComponentDescription=General Purpose Chip Resistor, 49.9 Ohm, +/- 1%, -55 to 155 degC, 0603 (1608 Metric), RoHS, Tape and Reel|PartCount=2|DisplayModeCount=1|IndexInSheet=56|OwnerPartId=-1|Location.X=1299|Location.Y=947|CurrentPartId=1|LibraryPath=*|SourceLibraryName=Altium Content Vault|TargetFileName=*|AreaColor=11599871|Color=128|PartIDLocked=T|DesignItemId=CMP-1659-00036-1|AllPinCount=2
|RECORD=2|OwnerIndex=588|OwnerPartId=1|FormalType=1|Electrical=4|PinConglomerate=32|PinLength=10|Location.X=1319|Location.Y=947|Name=2|Designator=2|PinPropagationDelay=0.000000E+000
|RECORD=2|OwnerIndex=588|OwnerPartId=1|FormalType=1|Electrical=4|PinConglomerate=34|PinLength=10|Location.X=1299|Location.Y=947|Name=1|Designator=1|PinPropagationDelay=0.000000E+000
|RECORD=6|OwnerIndex=588|IsNotAccesible=T|IndexInSheet=2|OwnerPartId=1|LineWidth=1|Color=16711680|LocationCount=10|X1=1319|Y1=947|X2=1315|Y2=947|X3=1314|Y3=945|X4=1312|Y4=949|X5=1310|Y5=945|X6=1308|Y6=949|X7=1306|Y7=945|X8=1304|Y8=949|X9=1303|Y9=947|X10=1299|Y10=947
|RECORD=41|OwnerIndex=588|IndexInSheet=3|OwnerPartId=-1|Location.X=1287|Location.Y=962|Color=8388608|FontID=1|IsHidden=T|Text=0603|Name=PackageReference
|RECORD=41|OwnerIndex=588|IndexInSheet=4|OwnerPartId=-1|Location.X=1287|Location.Y=962|Color=8388608|FontID=1|IsHidden=T|Text=Tray|Name=Packaging
|RECORD=41|OwnerIndex=588|IndexInSheet=5|OwnerPartId=-1|Location.X=1287|Location.Y=962|Color=8388608|FontID=1|IsHidden=T|Text=Datasheet|Name=ComponentLink2Description
|RECORD=41|OwnerIndex=588|IndexInSheet=6|OwnerPartId=-1|Location.X=1287|Location.Y=962|Color=8388608|FontID=1|IsHidden=T|Text=Manufacturer URL|Name=ComponentLink1Description
|RECORD=41|OwnerIndex=588|IndexInSheet=7|OwnerPartId=-1|Location.X=1287|Location.Y=962|Color=8388608|FontID=7|IsHidden=T|Text=https://datasheet.ciiva.com/11808/0900766b80f96399-11808223.pdf|Name=ComponentLink2URL
|RECORD=41|OwnerIndex=588|IndexInSheet=8|OwnerPartId=-1|Location.X=1287|Location.Y=962|Color=8388608|FontID=1|IsHidden=T|Text=true|Name=RoHSCompliant
|RECORD=41|OwnerIndex=588|IndexInSheet=9|OwnerPartId=-1|Location.X=1287|Location.Y=962|Color=8388608|FontID=1|IsHidden=T|Text=85 degC|Name=Max Operating Temperature
|RECORD=41|OwnerIndex=588|IndexInSheet=10|OwnerPartId=-1|Location.X=1287|Location.Y=962|Color=8388608|FontID=1|IsHidden=T|Text=3.63 V|Name=Max Supply Voltage
|RECORD=41|OwnerIndex=588|IndexInSheet=11|OwnerPartId=-1|Location.X=1287|Location.Y=962|Color=8388608|FontID=7|IsHidden=T|Text=http://www.yageo.com/|Name=ComponentLink1URL
|RECORD=41|OwnerIndex=588|IndexInSheet=12|OwnerPartId=-1|Location.X=1287|Location.Y=962|Color=8388608|FontID=1|IsHidden=T|Text=2-Pin Surface Mount Device, Body 1.6 x 0.8 mm|Name=PackageDescription
|RECORD=41|OwnerIndex=588|IndexInSheet=13|OwnerPartId=-1|Location.X=1287|Location.Y=962|Color=8388608|FontID=1|IsHidden=T|Text=LQFP|Name=Case\Package
|RECORD=41|OwnerIndex=588|IndexInSheet=14|OwnerPartId=-1|Location.X=1287|Location.Y=962|Color=8388608|FontID=1|IsHidden=T|Text=Rev. 4, 04/2009|Name=DatasheetVersion
|RECORD=41|OwnerIndex=588|IndexInSheet=15|OwnerPartId=-1|Location.X=1287|Location.Y=962|Color=8388608|FontID=1|IsHidden=T|Text=-40 degC|Name=Min Operating Temperature
|RECORD=41|OwnerIndex=588|IndexInSheet=16|OwnerPartId=-1|Location.X=1287|Location.Y=962|Color=8388608|FontID=1|IsHidden=T|Text=SPI|Name=Interface
|RECORD=41|OwnerIndex=588|IndexInSheet=17|OwnerPartId=-1|Location.X=1287|Location.Y=962|Color=8388608|FontID=1|IsHidden=T|Text=250|Name=Package Quantity
|RECORD=41|OwnerIndex=588|IndexInSheet=18|OwnerPartId=-1|Location.X=1287|Location.Y=962|Color=8388608|FontID=1|IsHidden=T|Text=2.97 V|Name=Min Supply Voltage
|RECORD=41|OwnerIndex=588|IndexInSheet=19|OwnerPartId=-1|Location.X=1287|Location.Y=962|Color=8388608|FontID=1|IsHidden=T|Text=48|Name=Pins
|RECORD=34|OwnerIndex=588|IndexInSheet=-1|OwnerPartId=-1|Location.X=1298|Location.Y=950|Color=8388608|FontID=1|Text=R28|Name=Designator|ReadOnlyState=1
|RECORD=41|OwnerIndex=588|IndexInSheet=-1|OwnerPartId=-1|Location.X=1298|Location.Y=934|Color=8388608|FontID=1|Text=49.9R|Name=Comment
|RECORD=44|OwnerIndex=588
|RECORD=45|OwnerIndex=613|IndexInSheet=-1|Description=Chip Resistor, 2-Leads, Body 1.70x0.90mm, IPC Medium Density|UseComponentLibrary=T|ModelName=RESC1608X55X25NL10T15|ModelType=PCBLIB|DatafileCount=1|ModelDatafileEntity0=RESC1608X55X25NL10T15|ModelDatafileKind0=PCBLib|IsCurrent=T|DatalinksLocked=T|DatabaseDatalinksLocked=T
|RECORD=46|OwnerIndex=614
|RECORD=48|OwnerIndex=614
|RECORD=41|OwnerIndex=616|IndexInSheet=-1|OwnerPartId=-1|Color=8388608|FontID=1|IsHidden=T|Text=2D|Name=Available Preview Images
|RECORD=45|OwnerIndex=613|IndexInSheet=-1|Description=Chip Resistor, 2-Leads, Body 1.70x0.90mm, IPC Low Density|UseComponentLibrary=T|ModelName=RESC1608X55X25ML10T15|ModelType=PCBLIB|DatafileCount=1|ModelDatafileEntity0=RESC1608X55X25ML10T15|ModelDatafileKind0=PCBLib|DatalinksLocked=T|DatabaseDatalinksLocked=T
|RECORD=46|OwnerIndex=618
|RECORD=48|OwnerIndex=618
|RECORD=41|OwnerIndex=620|IndexInSheet=-1|OwnerPartId=-1|Color=8388608|FontID=1|IsHidden=T|Text=2D|Name=Available Preview Images
|RECORD=45|OwnerIndex=613|IndexInSheet=-1|Description=Chip Resistor, 2-Leads, Body 1.70x0.90mm, IPC High Density|UseComponentLibrary=T|ModelName=RESC1608X55X25LL10T15|ModelType=PCBLIB|DatafileCount=1|ModelDatafileEntity0=RESC1608X55X25LL10T15|ModelDatafileKind0=PCBLib|DatalinksLocked=T|DatabaseDatalinksLocked=T
|RECORD=46|OwnerIndex=622
|RECORD=48|OwnerIndex=622
|RECORD=41|OwnerIndex=624|IndexInSheet=-1|OwnerPartId=-1|Color=8388608|FontID=1|IsHidden=T|Text=2D|Name=Available Preview Images
|RECORD=17|IndexInSheet=57|OwnerPartId=-1|ShowNetName=T|Location.X=1024|Location.Y=947|Orientation=2|Color=255|FontID=1|Text=ANT3_OUT|IsCrossSheetConnector=T
|RECORD=41|OwnerIndex=626|OwnerPartId=-1|Location.X=962|Location.X_Frac=7849|Location.Y=947|Orientation=2|Justification=3|Color=8388608|FontID=1|Text=FPGA[4A]|Name=CrossRef|ReadOnlyState=3
|RECORD=1|LibReference=RES-2|ComponentDescription=Precision Thick Film Chip Resistor, 4.7 KOhm, +/- 1%, -55 to 155 degC, 0603 (1608 Metric), RoHS, Tape and Reel ERJ-3EKF4701V|PartCount=2|DisplayModeCount=1|IndexInSheet=58|OwnerPartId=-1|Location.X=1034|Location.Y=1007|Orientation=1|CurrentPartId=1|LibraryPath=*|SourceLibraryName=Altium Content Vault|TargetFileName=*|AreaColor=11599871|Color=128|PartIDLocked=T|DesignItemId=CMP-1012-00586-3|AllPinCount=2
|RECORD=2|OwnerIndex=628|OwnerPartId=1|FormalType=1|Electrical=4|PinConglomerate=33|PinLength=10|Location.X=1034|Location.Y=1027|Name=2|Designator=2|PinPropagationDelay=0.000000E+000
|RECORD=2|OwnerIndex=628|OwnerPartId=1|FormalType=1|Electrical=4|PinConglomerate=35|PinLength=10|Location.X=1034|Location.Y=1007|Name=1|Designator=1|PinPropagationDelay=0.000000E+000
|RECORD=6|OwnerIndex=628|IsNotAccesible=T|IndexInSheet=2|OwnerPartId=1|LineWidth=1|Color=16711680|LocationCount=10|X1=1034|Y1=1027|X2=1034|Y2=1023|X3=1036|Y3=1022|X4=1032|Y4=1020|X5=1036|Y5=1018|X6=1032|Y6=1016|X7=1036|Y7=1014|X8=1032|Y8=1012|X9=1034|Y9=1011|X10=1034|Y10=1007
|RECORD=41|OwnerIndex=628|IndexInSheet=3|OwnerPartId=-1|Location.X=1031|Location.Y=1039|Color=8388608|FontID=1|IsHidden=T|Text=220 Ohm|Name=Resistance
|RECORD=41|OwnerIndex=628|IndexInSheet=4|OwnerPartId=-1|Location.X=1031|Location.Y=1039|Color=8388608|FontID=1|IsHidden=T|Text=0603|Name=PackageReference
|RECORD=41|OwnerIndex=628|IndexInSheet=5|OwnerPartId=-1|Location.X=1031|Location.Y=1039|Color=8388608|FontID=1|IsHidden=T|Text=50 V|Name=Voltage Rating
|RECORD=41|OwnerIndex=628|IndexInSheet=6|OwnerPartId=-1|Location.X=1031|Location.Y=1039|Color=8388608|FontID=1|IsHidden=T|Text=125 degC|Name=Max Operating Temperature
|RECORD=41|OwnerIndex=628|IndexInSheet=7|OwnerPartId=-1|Location.X=1031|Location.Y=1039|Color=8388608|FontID=1|IsHidden=T|Text=4|Name=Elements
|RECORD=41|OwnerIndex=628|IndexInSheet=8|OwnerPartId=-1|Location.X=1031|Location.Y=1039|Color=8388608|FontID=1|IsHidden=T|Text=No SVHC|Name=REACH SVHC
|RECORD=41|OwnerIndex=628|IndexInSheet=9|OwnerPartId=-1|Location.X=1031|Location.Y=1039|Color=8388608|FontID=1|IsHidden=T|Text=0.063 inch|Name=Width
|RECORD=41|OwnerIndex=628|IndexInSheet=10|OwnerPartId=-1|Location.X=1031|Location.Y=1039|Color=8388608|FontID=1|IsHidden=T|Text=1205|Name=Case\Package
|RECORD=41|OwnerIndex=628|IndexInSheet=11|OwnerPartId=-1|Location.X=1031|Location.Y=1039|Color=8388608|FontID=1|IsHidden=T|Text=0.126 inch|Name=Length
|RECORD=41|OwnerIndex=628|IndexInSheet=12|OwnerPartId=-1|Location.X=1031|Location.Y=1039|Color=8388608|FontID=1|IsHidden=T|Text=0.024 inch|Name=Height
|RECORD=41|OwnerIndex=628|IndexInSheet=13|OwnerPartId=-1|Location.X=1031|Location.Y=1039|Color=8388608|FontID=1|IsHidden=T|Text=Surface Mount|Name=Mount
|RECORD=41|OwnerIndex=628|IndexInSheet=14|OwnerPartId=-1|Location.X=1031|Location.Y=1039|Color=8388608|FontID=1|IsHidden=T|Text=1|Name=Package Quantity
|RECORD=41|OwnerIndex=628|IndexInSheet=15|OwnerPartId=-1|Location.X=1031|Location.Y=1039|Color=8388608|FontID=1|IsHidden=T|Text=Apr-15|Name=DatasheetVersion
|RECORD=41|OwnerIndex=628|IndexInSheet=16|OwnerPartId=-1|Location.X=1031|Location.Y=1039|Color=8388608|FontID=1|IsHidden=T|Text=Manufacturer URL|Name=ComponentLink1Description
|RECORD=41|OwnerIndex=628|IndexInSheet=17|OwnerPartId=-1|Location.X=1031|Location.Y=1039|Color=8388608|FontID=1|IsHidden=T|Text=-55 degC|Name=Min Operating Temperature
|RECORD=41|OwnerIndex=628|IndexInSheet=18|OwnerPartId=-1|Location.X=1031|Location.Y=1039|Color=8388608|FontID=1|IsHidden=T|Text=Tape and Reel|Name=Packaging
|RECORD=41|OwnerIndex=628|IndexInSheet=19|OwnerPartId=-1|Location.X=1031|Location.Y=1039|Color=8388608|FontID=1|IsHidden=T|Text=No|Name=Radiation Hardening
|RECORD=41|OwnerIndex=628|IndexInSheet=20|OwnerPartId=-1|Location.X=1031|Location.Y=1039|Color=8388608|FontID=7|IsHidden=T|Text=http://industrial.panasonic.com/cdbs/www-data/pdf/RDA0000/AOA0000C86.pdf|Name=ComponentLink2URL
|RECORD=41|OwnerIndex=628|IndexInSheet=21|OwnerPartId=-1|Location.X=1031|Location.Y=1039|Color=8388608|FontID=1|IsHidden=T|Text=3216|Name=Case Code (Metric)
|RECORD=41|OwnerIndex=628|IndexInSheet=22|OwnerPartId=-1|Location.X=1031|Location.Y=1039|Color=8388608|FontID=1|IsHidden=T|Text=8|Name=Pins
|RECORD=41|OwnerIndex=628|IndexInSheet=23|OwnerPartId=-1|Location.X=1031|Location.Y=1039|Color=8388608|FontID=1|IsHidden=T|Text=1206|Name=Case Code (Imperial)
|RECORD=41|OwnerIndex=628|IndexInSheet=24|OwnerPartId=-1|Location.X=1031|Location.Y=1039|Color=8388608|FontID=1|IsHidden=T|Text=Thick Film|Name=Type (Resistor)
|RECORD=41|OwnerIndex=628|IndexInSheet=25|OwnerPartId=-1|Location.X=1031|Location.Y=1039|Color=8388608|FontID=1|IsHidden=T|Text=true|Name=RoHSCompliant
|RECORD=41|OwnerIndex=628|IndexInSheet=26|OwnerPartId=-1|Location.X=1031|Location.Y=1039|Color=8388608|FontID=1|IsHidden=T|Text=5%|Name=Tolerance
|RECORD=41|OwnerIndex=628|IndexInSheet=27|OwnerPartId=-1|Location.X=1031|Location.Y=1039|Color=8388608|FontID=1|IsHidden=T|Text=Datasheet|Name=ComponentLink2Description
|RECORD=41|OwnerIndex=628|IndexInSheet=28|OwnerPartId=-1|Location.X=1031|Location.Y=1039|Color=8388608|FontID=1|IsHidden=T|Text=2-Pin Surface Mount Device, Body 1.6 x 0.85 mm|Name=PackageDescription
|RECORD=41|OwnerIndex=628|IndexInSheet=29|OwnerPartId=-1|Location.X=1031|Location.Y=1039|Color=8388608|FontID=7|IsHidden=T|Text=http://www.panasonic.com/|Name=ComponentLink1URL
|RECORD=41|OwnerIndex=628|IndexInSheet=30|OwnerPartId=-1|Location.X=1031|Location.Y=1039|Color=8388608|FontID=1|IsHidden=T|Text=250 mW|Name=Power Rating
|RECORD=34|OwnerIndex=628|IndexInSheet=-1|OwnerPartId=-1|Location.X=1037|Location.Y=1018|Color=8388608|FontID=1|Text=R16|Name=Designator|ReadOnlyState=1
|RECORD=41|OwnerIndex=628|IndexInSheet=-1|OwnerPartId=-1|Location.X=1037|Location.Y=1008|Color=8388608|FontID=1|Text=4.7K|Name=Comment
|RECORD=44|OwnerIndex=628
|RECORD=45|OwnerIndex=664|IndexInSheet=-1|Description=Chip Resistor, 2-Leads, Body 1.75x0.95mm, IPC Medium Density|UseComponentLibrary=T|ModelName=RESC1608X55X30NL15T15|ModelType=PCBLIB|DatafileCount=1|ModelDatafileEntity0=RESC1608X55X30NL15T15|ModelDatafileKind0=PCBLib|IsCurrent=T|DatalinksLocked=T|DatabaseDatalinksLocked=T
|RECORD=46|OwnerIndex=665
|RECORD=48|OwnerIndex=665
|RECORD=41|OwnerIndex=667|IndexInSheet=-1|OwnerPartId=-1|Color=8388608|FontID=1|IsHidden=T|Text=2D|Name=Available Preview Images
|RECORD=45|OwnerIndex=664|IndexInSheet=-1|Description=Chip Resistor, 2-Leads, Body 1.75x0.95mm, IPC Low Density|UseComponentLibrary=T|ModelName=RESC1608X55X30ML15T15|ModelType=PCBLIB|DatafileCount=1|ModelDatafileEntity0=RESC1608X55X30ML15T15|ModelDatafileKind0=PCBLib|DatalinksLocked=T|DatabaseDatalinksLocked=T
|RECORD=46|OwnerIndex=669
|RECORD=48|OwnerIndex=669
|RECORD=41|OwnerIndex=671|IndexInSheet=-1|OwnerPartId=-1|Color=8388608|FontID=1|IsHidden=T|Text=2D|Name=Available Preview Images
|RECORD=45|OwnerIndex=664|IndexInSheet=-1|Description=Chip Resistor, 2-Leads, Body 1.75x0.95mm, IPC High Density|UseComponentLibrary=T|ModelName=RESC1608X55X30LL15T15|ModelType=PCBLIB|DatafileCount=1|ModelDatafileEntity0=RESC1608X55X30LL15T15|ModelDatafileKind0=PCBLib|DatalinksLocked=T|DatabaseDatalinksLocked=T
|RECORD=46|OwnerIndex=673
|RECORD=48|OwnerIndex=673
|RECORD=41|OwnerIndex=675|IndexInSheet=-1|OwnerPartId=-1|Color=8388608|FontID=1|IsHidden=T|Text=2D|Name=Available Preview Images
|RECORD=1|LibReference=RES-2|ComponentDescription=Precision Thick Film Chip Resistor, 4.7 KOhm, +/- 1%, -55 to 155 degC, 0603 (1608 Metric), RoHS, Tape and Reel ERJ-3EKF4701V|PartCount=2|DisplayModeCount=1|IndexInSheet=59|OwnerPartId=-1|Location.X=1064|Location.Y=1007|Orientation=1|CurrentPartId=1|LibraryPath=*|SourceLibraryName=Altium Content Vault|TargetFileName=*|AreaColor=11599871|Color=128|PartIDLocked=T|DesignItemId=CMP-1012-00586-3|AllPinCount=2
|RECORD=2|OwnerIndex=677|OwnerPartId=1|FormalType=1|Electrical=4|PinConglomerate=33|PinLength=10|Location.X=1064|Location.Y=1027|Name=2|Designator=2|PinPropagationDelay=0.000000E+000
|RECORD=2|OwnerIndex=677|OwnerPartId=1|FormalType=1|Electrical=4|PinConglomerate=35|PinLength=10|Location.X=1064|Location.Y=1007|Name=1|Designator=1|PinPropagationDelay=0.000000E+000
|RECORD=6|OwnerIndex=677|IsNotAccesible=T|IndexInSheet=2|OwnerPartId=1|LineWidth=1|Color=16711680|LocationCount=10|X1=1064|Y1=1027|X2=1064|Y2=1023|X3=1066|Y3=1022|X4=1062|Y4=1020|X5=1066|Y5=1018|X6=1062|Y6=1016|X7=1066|Y7=1014|X8=1062|Y8=1012|X9=1064|Y9=1011|X10=1064|Y10=1007
|RECORD=41|OwnerIndex=677|IndexInSheet=3|OwnerPartId=-1|Location.X=1061|Location.Y=1039|Color=8388608|FontID=1|IsHidden=T|Text=220 Ohm|Name=Resistance
|RECORD=41|OwnerIndex=677|IndexInSheet=4|OwnerPartId=-1|Location.X=1061|Location.Y=1039|Color=8388608|FontID=1|IsHidden=T|Text=0603|Name=PackageReference
|RECORD=41|OwnerIndex=677|IndexInSheet=5|OwnerPartId=-1|Location.X=1061|Location.Y=1039|Color=8388608|FontID=1|IsHidden=T|Text=50 V|Name=Voltage Rating
|RECORD=41|OwnerIndex=677|IndexInSheet=6|OwnerPartId=-1|Location.X=1061|Location.Y=1039|Color=8388608|FontID=1|IsHidden=T|Text=125 degC|Name=Max Operating Temperature
|RECORD=41|OwnerIndex=677|IndexInSheet=7|OwnerPartId=-1|Location.X=1061|Location.Y=1039|Color=8388608|FontID=1|IsHidden=T|Text=4|Name=Elements
|RECORD=41|OwnerIndex=677|IndexInSheet=8|OwnerPartId=-1|Location.X=1061|Location.Y=1039|Color=8388608|FontID=1|IsHidden=T|Text=No SVHC|Name=REACH SVHC
|RECORD=41|OwnerIndex=677|IndexInSheet=9|OwnerPartId=-1|Location.X=1061|Location.Y=1039|Color=8388608|FontID=1|IsHidden=T|Text=0.063 inch|Name=Width
|RECORD=41|OwnerIndex=677|IndexInSheet=10|OwnerPartId=-1|Location.X=1061|Location.Y=1039|Color=8388608|FontID=1|IsHidden=T|Text=1205|Name=Case\Package
|RECORD=41|OwnerIndex=677|IndexInSheet=11|OwnerPartId=-1|Location.X=1061|Location.Y=1039|Color=8388608|FontID=1|IsHidden=T|Text=0.126 inch|Name=Length
|RECORD=41|OwnerIndex=677|IndexInSheet=12|OwnerPartId=-1|Location.X=1061|Location.Y=1039|Color=8388608|FontID=1|IsHidden=T|Text=0.024 inch|Name=Height
|RECORD=41|OwnerIndex=677|IndexInSheet=13|OwnerPartId=-1|Location.X=1061|Location.Y=1039|Color=8388608|FontID=1|IsHidden=T|Text=Surface Mount|Name=Mount
|RECORD=41|OwnerIndex=677|IndexInSheet=14|OwnerPartId=-1|Location.X=1061|Location.Y=1039|Color=8388608|FontID=1|IsHidden=T|Text=1|Name=Package Quantity
|RECORD=41|OwnerIndex=677|IndexInSheet=15|OwnerPartId=-1|Location.X=1061|Location.Y=1039|Color=8388608|FontID=1|IsHidden=T|Text=Apr-15|Name=DatasheetVersion
|RECORD=41|OwnerIndex=677|IndexInSheet=16|OwnerPartId=-1|Location.X=1061|Location.Y=1039|Color=8388608|FontID=1|IsHidden=T|Text=Manufacturer URL|Name=ComponentLink1Description
|RECORD=41|OwnerIndex=677|IndexInSheet=17|OwnerPartId=-1|Location.X=1061|Location.Y=1039|Color=8388608|FontID=1|IsHidden=T|Text=-55 degC|Name=Min Operating Temperature
|RECORD=41|OwnerIndex=677|IndexInSheet=18|OwnerPartId=-1|Location.X=1061|Location.Y=1039|Color=8388608|FontID=1|IsHidden=T|Text=Tape and Reel|Name=Packaging
|RECORD=41|OwnerIndex=677|IndexInSheet=19|OwnerPartId=-1|Location.X=1061|Location.Y=1039|Color=8388608|FontID=1|IsHidden=T|Text=No|Name=Radiation Hardening
|RECORD=41|OwnerIndex=677|IndexInSheet=20|OwnerPartId=-1|Location.X=1061|Location.Y=1039|Color=8388608|FontID=7|IsHidden=T|Text=http://industrial.panasonic.com/cdbs/www-data/pdf/RDA0000/AOA0000C86.pdf|Name=ComponentLink2URL
|RECORD=41|OwnerIndex=677|IndexInSheet=21|OwnerPartId=-1|Location.X=1061|Location.Y=1039|Color=8388608|FontID=1|IsHidden=T|Text=3216|Name=Case Code (Metric)
|RECORD=41|OwnerIndex=677|IndexInSheet=22|OwnerPartId=-1|Location.X=1061|Location.Y=1039|Color=8388608|FontID=1|IsHidden=T|Text=8|Name=Pins
|RECORD=41|OwnerIndex=677|IndexInSheet=23|OwnerPartId=-1|Location.X=1061|Location.Y=1039|Color=8388608|FontID=1|IsHidden=T|Text=1206|Name=Case Code (Imperial)
|RECORD=41|OwnerIndex=677|IndexInSheet=24|OwnerPartId=-1|Location.X=1061|Location.Y=1039|Color=8388608|FontID=1|IsHidden=T|Text=Thick Film|Name=Type (Resistor)
|RECORD=41|OwnerIndex=677|IndexInSheet=25|OwnerPartId=-1|Location.X=1061|Location.Y=1039|Color=8388608|FontID=1|IsHidden=T|Text=true|Name=RoHSCompliant
|RECORD=41|OwnerIndex=677|IndexInSheet=26|OwnerPartId=-1|Location.X=1061|Location.Y=1039|Color=8388608|FontID=1|IsHidden=T|Text=5%|Name=Tolerance
|RECORD=41|OwnerIndex=677|IndexInSheet=27|OwnerPartId=-1|Location.X=1061|Location.Y=1039|Color=8388608|FontID=1|IsHidden=T|Text=Datasheet|Name=ComponentLink2Description
|RECORD=41|OwnerIndex=677|IndexInSheet=28|OwnerPartId=-1|Location.X=1061|Location.Y=1039|Color=8388608|FontID=1|IsHidden=T|Text=2-Pin Surface Mount Device, Body 1.6 x 0.85 mm|Name=PackageDescription
|RECORD=41|OwnerIndex=677|IndexInSheet=29|OwnerPartId=-1|Location.X=1061|Location.Y=1039|Color=8388608|FontID=7|IsHidden=T|Text=http://www.panasonic.com/|Name=ComponentLink1URL
|RECORD=41|OwnerIndex=677|IndexInSheet=30|OwnerPartId=-1|Location.X=1061|Location.Y=1039|Color=8388608|FontID=1|IsHidden=T|Text=250 mW|Name=Power Rating
|RECORD=34|OwnerIndex=677|IndexInSheet=-1|OwnerPartId=-1|Location.X=1067|Location.Y=1018|Color=8388608|FontID=1|Text=R17|Name=Designator|ReadOnlyState=1
|RECORD=41|OwnerIndex=677|IndexInSheet=-1|OwnerPartId=-1|Location.X=1067|Location.Y=1008|Color=8388608|FontID=1|Text=4.7K|Name=Comment
|RECORD=44|OwnerIndex=677
|RECORD=45|OwnerIndex=713|IndexInSheet=-1|Description=Chip Resistor, 2-Leads, Body 1.75x0.95mm, IPC Medium Density|UseComponentLibrary=T|ModelName=RESC1608X55X30NL15T15|ModelType=PCBLIB|DatafileCount=1|ModelDatafileEntity0=RESC1608X55X30NL15T15|ModelDatafileKind0=PCBLib|IsCurrent=T|DatalinksLocked=T|DatabaseDatalinksLocked=T
|RECORD=46|OwnerIndex=714
|RECORD=48|OwnerIndex=714
|RECORD=41|OwnerIndex=716|IndexInSheet=-1|OwnerPartId=-1|Color=8388608|FontID=1|IsHidden=T|Text=2D|Name=Available Preview Images
|RECORD=45|OwnerIndex=713|IndexInSheet=-1|Description=Chip Resistor, 2-Leads, Body 1.75x0.95mm, IPC Low Density|UseComponentLibrary=T|ModelName=RESC1608X55X30ML15T15|ModelType=PCBLIB|DatafileCount=1|ModelDatafileEntity0=RESC1608X55X30ML15T15|ModelDatafileKind0=PCBLib|DatalinksLocked=T|DatabaseDatalinksLocked=T
|RECORD=46|OwnerIndex=718
|RECORD=48|OwnerIndex=718
|RECORD=41|OwnerIndex=720|IndexInSheet=-1|OwnerPartId=-1|Color=8388608|FontID=1|IsHidden=T|Text=2D|Name=Available Preview Images
|RECORD=45|OwnerIndex=713|IndexInSheet=-1|Description=Chip Resistor, 2-Leads, Body 1.75x0.95mm, IPC High Density|UseComponentLibrary=T|ModelName=RESC1608X55X30LL15T15|ModelType=PCBLIB|DatafileCount=1|ModelDatafileEntity0=RESC1608X55X30LL15T15|ModelDatafileKind0=PCBLib|DatalinksLocked=T|DatabaseDatalinksLocked=T
|RECORD=46|OwnerIndex=722
|RECORD=48|OwnerIndex=722
|RECORD=41|OwnerIndex=724|IndexInSheet=-1|OwnerPartId=-1|Color=8388608|FontID=1|IsHidden=T|Text=2D|Name=Available Preview Images
|RECORD=17|IndexInSheet=60|OwnerPartId=-1|ShowNetName=T|Location.X=1034|Location.Y=1037|Orientation=1|Color=128|FontID=1|Text=+3.3V
|RECORD=17|IndexInSheet=61|OwnerPartId=-1|ShowNetName=T|Location.X=1064|Location.Y=1037|Orientation=1|Color=128|FontID=1|Text=+3.3V
|RECORD=17|IndexInSheet=62|OwnerPartId=-1|ShowNetName=T|Location.X=1024|Location.Y=892|Orientation=2|Color=255|FontID=1|Text=ANT3_IN|IsCrossSheetConnector=T
|RECORD=41|OwnerIndex=728|OwnerPartId=-1|Location.X=971|Location.X_Frac=1146|Location.Y=892|Orientation=2|Justification=3|Color=8388608|FontID=1|Text=FPGA[5A]|Name=CrossRef|ReadOnlyState=3
|RECORD=1|LibReference=CAP|ComponentDescription=C0603X104K5RACAUTO|PartCount=2|DisplayModeCount=2|IndexInSheet=63|OwnerPartId=-1|Location.X=1104|Location.Y=847|Orientation=3|CurrentPartId=1|SourceLibraryName=Altium Content Vault|TargetFileName=*|AreaColor=11599871|Color=128|PartIDLocked=F|DesignItemId=CMP-2006-00003-1|AllPinCount=2
|RECORD=2|OwnerIndex=730|OwnerPartId=1|OwnerPartDisplayMode=1|FormalType=1|Electrical=4|PinConglomerate=33|PinLength=10|Location.X=1094|Location.Y=847|Name=1|Designator=1|PinPropagationDelay=0.000000E+000
|RECORD=2|OwnerIndex=730|OwnerPartId=1|OwnerPartDisplayMode=1|FormalType=1|Electrical=4|PinConglomerate=35|PinLength=10|Location.X=1094|Location.Y=837|Name=2|Designator=2|PinPropagationDelay=0.000000E+000
|RECORD=13|OwnerIndex=730|IsNotAccesible=T|IndexInSheet=2|OwnerPartId=1|OwnerPartDisplayMode=1|Location.X=1086|Location.Y=847|Corner.X=1102|Corner.Y=847|LineWidth=1|Color=16711680
|RECORD=13|OwnerIndex=730|IsNotAccesible=T|IndexInSheet=3|OwnerPartId=1|OwnerPartDisplayMode=1|Location.X=1094|Location.Y=843|Corner.X=1094|Corner.Y=837|LineWidth=1|Color=16711680
|RECORD=12|OwnerIndex=730|IsNotAccesible=T|IndexInSheet=4|OwnerPartId=1|OwnerPartDisplayMode=1|Location.X=1094|Location.Y=827|Radius=16|LineWidth=1|StartAngle=61.000|EndAngle=90.000|Color=16711680
|RECORD=12|OwnerIndex=730|IsNotAccesible=T|IndexInSheet=5|OwnerPartId=1|OwnerPartDisplayMode=1|Location.X=1094|Location.Y=827|Radius=16|LineWidth=1|StartAngle=90.000|EndAngle=119.000|Color=16711680
|RECORD=2|OwnerIndex=730|OwnerPartId=1|FormalType=1|Electrical=4|PinConglomerate=33|PinLength=10|Location.X=1094|Location.Y=847|Name=1|Designator=1|PinPropagationDelay=0.000000E+000
|RECORD=2|OwnerIndex=730|OwnerPartId=1|FormalType=1|Electrical=4|PinConglomerate=35|PinLength=10|Location.X=1094|Location.Y=837|Name=2|Designator=2|PinPropagationDelay=0.000000E+000
|RECORD=13|OwnerIndex=730|IsNotAccesible=T|IndexInSheet=8|OwnerPartId=1|Location.X=1102|Location.Y=840|Corner.X=1086|Corner.Y=840|LineWidth=1|Color=16711680
|RECORD=13|OwnerIndex=730|IsNotAccesible=T|IndexInSheet=9|OwnerPartId=1|Location.X=1086|Location.Y=844|Corner.X=1102|Corner.Y=844|LineWidth=1|Color=16711680
|RECORD=6|OwnerIndex=730|IsNotAccesible=T|IndexInSheet=10|OwnerPartId=1|LineWidth=1|Color=16711680|LocationCount=2|X1=1094|Y1=847|X2=1094|Y2=844
|RECORD=6|OwnerIndex=730|IsNotAccesible=T|IndexInSheet=11|OwnerPartId=1|LineWidth=1|Color=16711680|LocationCount=2|X1=1094|Y1=837|X2=1094|Y2=840
|RECORD=41|OwnerIndex=730|IndexInSheet=12|OwnerPartId=-1|Location.X=1085|Location.Y=859|Color=8388608|FontID=1|IsHidden=T|Text=Kemet|Name=Manufacturer
|RECORD=41|OwnerIndex=730|IndexInSheet=13|OwnerPartId=-1|Location.X=1085|Location.Y=859|Color=8388608|FontID=1|IsHidden=T|Text=C0603X104K5RACAUTO|Name=Part Number
|RECORD=34|OwnerIndex=730|IndexInSheet=-1|OwnerPartId=-1|Location.X=1103|Location.Y=834|Color=8388608|FontID=1|Text=C27|Name=Designator|ReadOnlyState=1
|RECORD=41|OwnerIndex=730|IndexInSheet=-1|OwnerPartId=-1|Location.X=1103|Location.Y=820|Color=8388608|FontID=1|Text=0.1uF|Name=Comment
|RECORD=44|OwnerIndex=730
|RECORD=45|OwnerIndex=751|IndexInSheet=-1|Description=Chip Capacitor, 2-Leads, Body 1.60x0.80mm, IPC Low Density|UseComponentLibrary=T|ModelName=CAPC1608X87X45ML20T05|ModelType=PCBLIB|DatafileCount=1|ModelDatafileEntity0=CAPC1608X87X45ML20T05|ModelDatafileKind0=PCBLib|IsCurrent=T|DatalinksLocked=T|DatabaseDatalinksLocked=T
|RECORD=46|OwnerIndex=752
|RECORD=48|OwnerIndex=752
|RECORD=41|OwnerIndex=754|IndexInSheet=-1|OwnerPartId=-1|Color=8388608|FontID=1|Text=2D|Name=Available Preview Images
|RECORD=45|OwnerIndex=751|IndexInSheet=-1|Description=Chip Capacitor, 2-Leads, Body 1.60x0.80mm, IPC High Density|UseComponentLibrary=T|ModelName=CAPC1608X87X45LL20T05|ModelType=PCBLIB|DatafileCount=1|ModelDatafileEntity0=CAPC1608X87X45LL20T05|ModelDatafileKind0=PCBLib|DatalinksLocked=T|DatabaseDatalinksLocked=T
|RECORD=46|OwnerIndex=756
|RECORD=48|OwnerIndex=756
|RECORD=41|OwnerIndex=758|IndexInSheet=-1|OwnerPartId=-1|Color=8388608|FontID=1|Text=2D|Name=Available Preview Images
|RECORD=45|OwnerIndex=751|IndexInSheet=-1|Description=Chip Capacitor, 2-Leads, Body 1.60x0.80mm, IPC Medium Density|UseComponentLibrary=T|ModelName=CAPC1608X87X45NL20T05|ModelType=PCBLIB|DatafileCount=1|ModelDatafileEntity0=CAPC1608X87X45NL20T05|ModelDatafileKind0=PCBLib|DatalinksLocked=T|DatabaseDatalinksLocked=T
|RECORD=46|OwnerIndex=760
|RECORD=48|OwnerIndex=760
|RECORD=41|OwnerIndex=762|IndexInSheet=-1|OwnerPartId=-1|Color=8388608|FontID=1|Text=2D|Name=Available Preview Images
|RECORD=17|IndexInSheet=64|OwnerPartId=-1|Style=4|ShowNetName=T|Location.X=1144|Location.Y=817|Orientation=3|Color=128|FontID=1|Text=GND
|RECORD=17|IndexInSheet=65|OwnerPartId=-1|Style=4|ShowNetName=T|Location.X=1094|Location.Y=817|Orientation=3|Color=128|FontID=1|Text=GND
|RECORD=17|IndexInSheet=66|OwnerPartId=-1|ShowNetName=T|Location.X=1094|Location.Y=1037|Orientation=1|Color=128|FontID=1|Text=+3.3V
|RECORD=1|LibReference=NC7WV125K8X|ComponentDescription=Integrated Circuit|PartCount=2|DisplayModeCount=1|IndexInSheet=67|OwnerPartId=-1|Location.X=1154|Location.Y=552|CurrentPartId=1|LibraryPath=*|SourceLibraryName=SamacSys.SchLib|TargetFileName=*|AreaColor=11599871|Color=128|PartIDLocked=T|DesignItemId=NC7WV125K8X|AllPinCount=8
|RECORD=41|OwnerIndex=767|OwnerPartId=-1|Location.X=1154|Location.Y=552|Color=8388608|FontID=7|IsHidden=T|Text=https://www.mouser.com/datasheet/2/308/NC7WV125-1301459.pdf|Name=Datasheet Link
|RECORD=41|OwnerIndex=767|IndexInSheet=1|OwnerPartId=-1|Location.X=1154|Location.Y=552|Color=8388608|FontID=1|IsHidden=T|Text=0.9mm|Name=Height
|RECORD=41|OwnerIndex=767|IndexInSheet=2|OwnerPartId=-1|Location.X=1154|Location.Y=552|Color=8388608|FontID=1|IsHidden=T|Text=ON Semiconductor|Name=Manufacturer_Name
|RECORD=41|OwnerIndex=767|IndexInSheet=3|OwnerPartId=-1|Location.X=1154|Location.Y=552|Color=8388608|FontID=1|IsHidden=T|Text=NC7WV125K8X|Name=Manufacturer_Part_Number
|RECORD=41|OwnerIndex=767|IndexInSheet=4|OwnerPartId=-1|Location.X=1154|Location.Y=552|Color=8388608|FontID=1|IsHidden=T|Text=512-NC7WV125K8X|Name=Mouser Part Number
|RECORD=41|OwnerIndex=767|IndexInSheet=5|OwnerPartId=-1|Location.X=1154|Location.Y=552|Color=8388608|FontID=7|IsHidden=T|Text=https://www.mouser.com/Search/Refine.aspx?Keyword=512-NC7WV125K8X|Name=Mouser Price/Stock
|RECORD=41|OwnerIndex=767|IndexInSheet=6|OwnerPartId=-1|Location.X=1154|Location.Y=552|Color=8388608|FontID=1|IsHidden=T|Text=NC7WV125K8X|Name=Arrow Part Number
|RECORD=41|OwnerIndex=767|IndexInSheet=7|OwnerPartId=-1|Location.X=1154|Location.Y=552|Color=8388608|FontID=7|IsHidden=T|Text=https://www.arrow.com/en/products/nc7wv125k8x/on-semiconductor|Name=Arrow Price/Stock
|RECORD=14|OwnerIndex=767|IsNotAccesible=T|IndexInSheet=8|OwnerPartId=1|Location.X=1174|Location.Y=527|Corner.X=1244|Corner.Y=652|LineWidth=1|Color=128|AreaColor=11599871|IsSolid=T
|RECORD=2|OwnerIndex=767|OwnerPartId=1|FormalType=1|Electrical=4|PinConglomerate=58|PinLength=20|Location.X=1174|Location.Y=642|Designator=1|SwapIDPart=Ž&Ž||PinPropagationDelay=0.000000E+000
|RECORD=2|OwnerIndex=767|OwnerPartId=1|FormalType=1|Electrical=4|PinConglomerate=58|PinLength=20|Location.X=1174|Location.Y=617|Designator=2|SwapIDPart=Ž&Ž||PinPropagationDelay=0.000000E+000
|RECORD=2|OwnerIndex=767|OwnerPartId=1|FormalType=1|Electrical=4|PinConglomerate=58|PinLength=20|Location.X=1174|Location.Y=562|Designator=3|SwapIDPart=Ž&Ž||PinPropagationDelay=0.000000E+000
|RECORD=2|OwnerIndex=767|OwnerPartId=1|FormalType=1|Electrical=4|PinConglomerate=58|PinLength=20|Location.X=1174|Location.Y=532|Name=GND|Designator=4|SwapIDPart=Ž&Ž||PinPropagationDelay=0.000000E+000
|RECORD=2|OwnerIndex=767|OwnerPartId=1|FormalType=1|Electrical=4|PinConglomerate=58|PinLength=20|Location.X=1174|Location.Y=542|Name=VCC|Designator=8|SwapIDPart=Ž&Ž||PinPropagationDelay=0.000000E+000
|RECORD=2|OwnerIndex=767|OwnerPartId=1|FormalType=1|Electrical=4|PinConglomerate=58|PinLength=20|Location.X=1174|Location.Y=587|Designator=7|SwapIDPart=Ž&Ž||PinPropagationDelay=0.000000E+000
|RECORD=2|OwnerIndex=767|OwnerPartId=1|FormalType=1|Electrical=4|PinConglomerate=56|PinLength=20|Location.X=1244|Location.Y=617|Designator=6|SwapIDPart=Ž&Ž||PinPropagationDelay=0.000000E+000
|RECORD=2|OwnerIndex=767|OwnerPartId=1|FormalType=1|Electrical=4|PinConglomerate=56|PinLength=20|Location.X=1244|Location.Y=562|Designator=5|SwapIDPart=Ž&Ž||PinPropagationDelay=0.000000E+000
|RECORD=6|OwnerIndex=767|IsNotAccesible=T|IndexInSheet=17|OwnerPartId=1|LineWidth=1|Color=16711680|LocationCount=4|X1=1199|Y1=627|X2=1199|Y2=607|X3=1219|Y3=617|X4=1199|Y4=627
|RECORD=12|OwnerIndex=767|IsNotAccesible=T|IndexInSheet=18|OwnerPartId=1|Location.X=1209|Location.Y=624|Radius=1|Radius_Frac=79777|LineWidth=1|EndAngle=360.000|Color=16711680
|RECORD=6|OwnerIndex=767|IsNotAccesible=T|IndexInSheet=19|OwnerPartId=1|LineWidth=1|Color=16711680|LocationCount=4|X1=1219|Y1=572|X2=1219|Y2=552|X3=1199|Y3=562|X4=1219|Y4=572
|RECORD=12|OwnerIndex=767|IsNotAccesible=T|IndexInSheet=20|OwnerPartId=1|Location.X=1209|Location.Y=569|Radius=1|Radius_Frac=79777|LineWidth=1|EndAngle=360.000|Color=16711680
|RECORD=6|OwnerIndex=767|IsNotAccesible=T|IndexInSheet=21|OwnerPartId=1|LineWidth=1|Color=16711680|LocationCount=3|X1=1209|Y1=571|X2=1209|Y2=587|X3=1174|Y3=587
|RECORD=6|OwnerIndex=767|IsNotAccesible=T|IndexInSheet=22|OwnerPartId=1|LineWidth=1|Color=16711680|LocationCount=3|X1=1209|Y1=626|X2=1209|Y2=642|X3=1174|Y3=642
|RECORD=6|OwnerIndex=767|IsNotAccesible=T|IndexInSheet=23|OwnerPartId=1|LineWidth=1|Color=16711680|LocationCount=2|X1=1174|Y1=617|X2=1199|Y2=617
|RECORD=6|OwnerIndex=767|IsNotAccesible=T|IndexInSheet=24|OwnerPartId=1|LineWidth=1|Color=16711680|LocationCount=2|X1=1219|Y1=617|X2=1244|Y2=617
|RECORD=6|OwnerIndex=767|IsNotAccesible=T|IndexInSheet=25|OwnerPartId=1|LineWidth=1|Color=16711680|LocationCount=2|X1=1219|Y1=562|X2=1244|Y2=562
|RECORD=6|OwnerIndex=767|IsNotAccesible=T|IndexInSheet=26|OwnerPartId=1|LineWidth=1|Color=16711680|LocationCount=2|X1=1199|Y1=562|X2=1174|Y2=562
|RECORD=34|OwnerIndex=767|IndexInSheet=-1|OwnerPartId=-1|Location.X=1173|Location.Y=652|Color=8388608|FontID=1|Text=U16|Name=Designator|ReadOnlyState=1
|RECORD=41|OwnerIndex=767|IndexInSheet=-1|OwnerPartId=-1|Location.X=1173|Location.Y=517|Color=8388608|FontID=1|Text=NC7WV125K8X|Name=Comment
|RECORD=44|OwnerIndex=767
|RECORD=45|OwnerIndex=805|IndexInSheet=-1|ModelName=SOP50P310X90-8N|ModelType=PCBLIB|DatafileCount=1|ModelDatafile0=C:\Users\<user>\Documents\AltiumLL\SamacSys.PcbLib|ModelDatafileEntity0=SOP50P310X90-8N|ModelDatafileKind0=PCBLIB|IsCurrent=T
|RECORD=46|OwnerIndex=806
|RECORD=48|OwnerIndex=806
|RECORD=1|LibReference=CN-1P-M-RF3|ComponentDescription=Ultra Miniature Coaxial Connector Jack, 60 V, 50 Ohm, -40 to 90 degC, RoHS, Tape and Reel|PartCount=2|DisplayModeCount=1|IndexInSheet=68|OwnerPartId=-1|Location.X=1394|Location.Y=637|CurrentPartId=1|LibraryPath=*|SourceLibraryName=Altium Content Vault|TargetFileName=*|AreaColor=11599871|Color=128|PartIDLocked=T|DesignItemId=CMP-2000-07505-1|AllPinCount=3
|RECORD=8|OwnerIndex=809|IsNotAccesible=T|OwnerPartId=1|Location.X=1414|Location.Y=617|Radius=20|SecondaryRadius=20|LineWidth=1|Color=16711680|AreaColor=16777215
|RECORD=8|OwnerIndex=809|IsNotAccesible=T|IndexInSheet=1|OwnerPartId=1|Location.X=1414|Location.Y=617|Radius=4|SecondaryRadius=4|LineWidth=1|Color=16711680|AreaColor=16777215
|RECORD=2|OwnerIndex=809|OwnerPartId=1|FormalType=1|Electrical=4|PinConglomerate=51|PinLength=10|Location.X=1404|Location.Y=597|Name=1|Designator=1|PinPropagationDelay=0.000000E+000
|RECORD=2|OwnerIndex=809|OwnerPartId=1|FormalType=1|Electrical=4|PinConglomerate=50|PinLength=10|Location.X=1394|Location.Y=617|Name=2|Designator=2|PinPropagationDelay=0.000000E+000
|RECORD=2|OwnerIndex=809|OwnerPartId=1|FormalType=1|Electrical=4|PinConglomerate=51|PinLength=10|Location.X=1424|Location.Y=597|Name=3|Designator=3|PinPropagationDelay=0.000000E+000
|RECORD=6|OwnerIndex=809|IsNotAccesible=T|IndexInSheet=5|OwnerPartId=1|LineWidth=1|Color=16711680|LocationCount=5|X1=1394|Y1=597|X2=1394|Y2=637|X3=1434|Y3=637|X4=1434|Y4=597|X5=1394|Y5=597
|RECORD=6|OwnerIndex=809|IsNotAccesible=T|IndexInSheet=6|OwnerPartId=1|LineWidth=1|Color=16711680|LocationCount=2|X1=1394|Y1=617|X2=1410|Y2=617
|RECORD=41|OwnerIndex=809|IndexInSheet=7|OwnerPartId=-1|Location.X=1382|Location.Y=638|Color=8388608|FontID=1|IsHidden=T|Text=Straight|Name=Orientation
|RECORD=41|OwnerIndex=809|IndexInSheet=8|OwnerPartId=-1|Location.X=1382|Location.Y=638|Color=8388608|FontID=1|IsHidden=T|Text=Female|Name=Gender
|RECORD=41|OwnerIndex=809|IndexInSheet=9|OwnerPartId=-1|Location.X=1382|Location.Y=638|Color=8388608|FontID=1|IsHidden=T|Text=Vertical|Name=PCB Mounting Orientation
|RECORD=41|OwnerIndex=809|IndexInSheet=10|OwnerPartId=-1|Location.X=1382|Location.Y=638|Color=8388608|FontID=1|IsHidden=T|Text=SurfaceMount|Name=Mount
|RECORD=41|OwnerIndex=809|IndexInSheet=11|OwnerPartId=-1|Location.X=1382|Location.Y=638|Color=8388608|FontID=1|IsHidden=T|Text=3mm|Name=Length
|RECORD=41|OwnerIndex=809|IndexInSheet=12|OwnerPartId=-1|Location.X=1382|Location.Y=638|Color=8388608|FontID=1|IsHidden=T|Text=TapeandReel|Name=Packaging
|RECORD=41|OwnerIndex=809|IndexInSheet=13|OwnerPartId=-1|Location.X=1382|Location.Y=638|Color=8388608|FontID=1|IsHidden=T|Text=Jack|Name=Connector Type
|RECORD=41|OwnerIndex=809|IndexInSheet=14|OwnerPartId=-1|Location.X=1382|Location.Y=638|Color=8388608|FontID=1|IsHidden=T|Text=LeadFree|Name=Lead Free
|RECORD=41|OwnerIndex=809|IndexInSheet=15|OwnerPartId=-1|Location.X=1382|Location.Y=638|Color=8388608|FontID=1|IsHidden=T|Text=1|Name=Package Quantity
|RECORD=41|OwnerIndex=809|IndexInSheet=16|OwnerPartId=-1|Location.X=1382|Location.Y=638|Color=8388608|FontID=1|IsHidden=T|Text=SMD/SMT|Name=Termination
|RECORD=41|OwnerIndex=809|IndexInSheet=17|OwnerPartId=-1|Location.X=1382|Location.Y=638|Color=8388608|FontID=1|IsHidden=T|Text=CopperAlloy|Name=Contact Material
|RECORD=41|OwnerIndex=809|IndexInSheet=18|OwnerPartId=-1|Location.X=1382|Location.Y=638|Color=8388608|FontID=1|IsHidden=T|Text=Pull|Name=Fastening Type
|RECORD=41|OwnerIndex=809|IndexInSheet=19|OwnerPartId=-1|Location.X=1382|Location.Y=638|Color=8388608|FontID=1|IsHidden=T|Text=true|Name=RoHSCompliant
|RECORD=41|OwnerIndex=809|IndexInSheet=20|OwnerPartId=-1|Location.X=1382|Location.Y=638|Color=8388608|FontID=1|IsHidden=T|Text=LiquidCrystalPolymer|Name=Body Material
|RECORD=41|OwnerIndex=809|IndexInSheet=21|OwnerPartId=-1|Location.X=1382|Location.Y=638|Color=8388608|FontID=1|IsHidden=T|Text=SMD/SMT|Name=Case\/Package
|RECORD=41|OwnerIndex=809|IndexInSheet=22|OwnerPartId=-1|Location.X=1382|Location.Y=638|Color=8388608|FontID=1|IsHidden=T|Text=90degC|Name=Max Operating Temperature
|RECORD=41|OwnerIndex=809|IndexInSheet=23|OwnerPartId=-1|Location.X=1382|Location.Y=638|Color=8388608|FontID=1|IsHidden=T|Text=50Ohm|Name=Impedance
|RECORD=41|OwnerIndex=809|IndexInSheet=24|OwnerPartId=-1|Location.X=1382|Location.Y=638|Color=8388608|FontID=7|IsHidden=T|Text=http://www.te.com/commerce/DocumentDelivery/DDEController?Action=srchrtrv&DocNm=1909763&DocType=Customer+Drawing&DocLang=English|Name=Datasheet URL
|RECORD=41|OwnerIndex=809|IndexInSheet=25|OwnerPartId=-1|Location.X=1382|Location.Y=638|Color=8388608|FontID=1|IsHidden=T|Text=Gold|Name=Contact Plating
|RECORD=41|OwnerIndex=809|IndexInSheet=26|OwnerPartId=-1|Location.X=1382|Location.Y=638|Color=8388608|FontID=1|IsHidden=T|Text=SurfaceMount|Name=Mounting Technology
|RECORD=41|OwnerIndex=809|IndexInSheet=27|OwnerPartId=-1|Location.X=1382|Location.Y=638|Color=8388608|FontID=1|IsHidden=T|Text=6GHz|Name=Max Frequency
|RECORD=41|OwnerIndex=809|IndexInSheet=28|OwnerPartId=-1|Location.X=1382|Location.Y=638|Color=8388608|FontID=1|IsHidden=T|Text=TECO-1909763-1|Name=Package Reference
|RECORD=41|OwnerIndex=809|IndexInSheet=29|OwnerPartId=-1|Location.X=1382|Location.Y=638|Color=8388608|FontID=1|IsHidden=T|Text=Thermoplastic|Name=Insulation Material
|RECORD=41|OwnerIndex=809|IndexInSheet=30|OwnerPartId=-1|Location.X=1382|Location.Y=638|Color=8388608|FontID=1|IsHidden=T|Text=-40degC|Name=Min Operating Temperature
|RECORD=41|OwnerIndex=809|IndexInSheet=31|OwnerPartId=-1|Location.X=1382|Location.Y=638|Color=8388608|FontID=7|IsHidden=T|Text=http://www.te.com/|Name=Manufacturer URL
|RECORD=41|OwnerIndex=809|IndexInSheet=32|OwnerPartId=-1|Location.X=1382|Location.Y=638|Color=8388608|FontID=1|IsHidden=T|Text=Gold|Name=Body Plating
|RECORD=41|OwnerIndex=809|IndexInSheet=33|OwnerPartId=-1|Location.X=1382|Location.Y=638|Color=8388608|FontID=1|IsHidden=T|Text=Polymer|Name=Dielectric Material
|RECORD=41|OwnerIndex=809|IndexInSheet=34|OwnerPartId=-1|Location.X=1382|Location.Y=638|Color=8388608|FontID=1|IsHidden=T|Text=TE Connectivity|Name=Manufacturer
|RECORD=41|OwnerIndex=809|IndexInSheet=35|OwnerPartId=-1|Location.X=1382|Location.Y=638|Color=8388608|FontID=1|IsHidden=T|Text=Compliant|Name=ELV
|RECORD=41|OwnerIndex=809|IndexInSheet=36|OwnerPartId=-1|Location.X=1382|Location.Y=638|Color=8388608|FontID=1|IsHidden=T|Text=Rev. B2, 11/2015|Name=Datasheet Version
|RECORD=41|OwnerIndex=809|IndexInSheet=37|OwnerPartId=-1|Location.X=1382|Location.Y=638|Color=8388608|FontID=1|IsHidden=T|Text=No|Name=Radiation Hardening
|RECORD=41|OwnerIndex=809|IndexInSheet=38|OwnerPartId=-1|Location.X=1382|Location.Y=638|Color=8388608|FontID=1|IsHidden=T|Text=3-Pin Surface Mount Device, Body 2.6 x 2.6 mm|Name=Package Description
|RECORD=41|OwnerIndex=809|IndexInSheet=39|OwnerPartId=-1|Location.X=1382|Location.Y=638|Color=8388608|FontID=1|IsHidden=T|Text=Beige|Name=Housing Colour
|RECORD=34|OwnerIndex=809|IndexInSheet=-1|OwnerPartId=-1|Location.X=1393|Location.Y=638|Color=8388608|FontID=1|Text=J4|Name=Designator|ReadOnlyState=1
|RECORD=41|OwnerIndex=809|IndexInSheet=-1|OwnerPartId=-1|Location.X=1444|Location.Y=597|Color=8388608|FontID=1|Text=1909763-1|Name=Comment
|RECORD=44|OwnerIndex=809
|RECORD=45|OwnerIndex=855|IndexInSheet=-1|Description=SMD, 3-Leads, Body 2.6x2.6mm, Height 1.25mm|UseComponentLibrary=T|ModelName=TECO-1909763-1_V|ModelType=PCBLIB|DatafileCount=1|ModelDatafileEntity0=TECO-1909763-1_V|ModelDatafileKind0=PCBLib|IsCurrent=T|DatalinksLocked=T|DatabaseDatalinksLocked=T
|RECORD=46|OwnerIndex=856
|RECORD=48|OwnerIndex=856
|RECORD=41|OwnerIndex=858|IndexInSheet=-1|OwnerPartId=-1|Color=8388608|FontID=1|Text=2D|Name=Available Preview Images
|RECORD=1|LibReference=CN-S-4F-RF5|ComponentDescription=Coaxial connector, 50 Ohm, -65 to 165 degC, 5-Pin THD, RoHS, Bulk|PartCount=2|DisplayModeCount=1|IndexInSheet=69|OwnerPartId=-1|Location.X=1394|Location.Y=557|CurrentPartId=1|LibraryPath=*|SourceLibraryName=Altium Content Vault|TargetFileName=*|AreaColor=11599871|Color=128|PartIDLocked=T|DesignItemId=CMP-2000-05705-1|AllPinCount=5
|RECORD=2|OwnerIndex=860|OwnerPartId=1|FormalType=1|Electrical=4|PinConglomerate=51|PinLength=10|Location.X=1434|Location.Y=517|Name=5|Designator=5|SwapIDPart=Ž&Ž1|PinPropagationDelay=0.000000E+000
|RECORD=8|OwnerIndex=860|IsNotAccesible=T|IndexInSheet=1|OwnerPartId=1|Location.X=1414|Location.Y=537|Radius=20|SecondaryRadius=20|LineWidth=1|Color=16711680|AreaColor=16777215
|RECORD=8|OwnerIndex=860|IsNotAccesible=T|IndexInSheet=2|OwnerPartId=1|Location.X=1414|Location.Y=537|Radius=4|SecondaryRadius=4|LineWidth=1|Color=16711680|AreaColor=16777215
|RECORD=2|OwnerIndex=860|OwnerPartId=1|FormalType=1|Electrical=4|PinConglomerate=50|PinLength=10|Location.X=1394|Location.Y=537|Name=1|Designator=1|PinPropagationDelay=0.000000E+000
|RECORD=2|OwnerIndex=860|OwnerPartId=1|FormalType=1|Electrical=4|PinConglomerate=51|PinLength=10|Location.X=1404|Location.Y=517|Name=2|Designator=2|PinPropagationDelay=0.000000E+000
|RECORD=2|OwnerIndex=860|OwnerPartId=1|FormalType=1|Electrical=4|PinConglomerate=51|PinLength=10|Location.X=1414|Location.Y=517|Name=3|Designator=3|PinPropagationDelay=0.000000E+000
|RECORD=2|OwnerIndex=860|OwnerPartId=1|FormalType=1|Electrical=4|PinConglomerate=51|PinLength=10|Location.X=1424|Location.Y=517|Name=4|Designator=4|PinPropagationDelay=0.000000E+000
|RECORD=6|OwnerIndex=860|IsNotAccesible=T|IndexInSheet=7|OwnerPartId=1|LineWidth=1|Color=16711680|LocationCount=5|X1=1394|Y1=517|X2=1394|Y2=557|X3=1434|Y3=557|X4=1434|Y4=517|X5=1394|Y5=517
|RECORD=6|OwnerIndex=860|IsNotAccesible=T|IndexInSheet=8|OwnerPartId=1|LineWidth=1|Color=16711680|LocationCount=2|X1=1394|Y1=537|X2=1410|Y2=537
|RECORD=41|OwnerIndex=860|IndexInSheet=9|OwnerPartId=-1|Location.X=1382|Location.Y=558|Color=8388608|FontID=1|IsHidden=T|Text=ThroughHole|Name=Mounting Technology
|RECORD=41|OwnerIndex=860|IndexInSheet=10|OwnerPartId=-1|Location.X=1382|Location.Y=558|Color=8388608|FontID=1|IsHidden=T|Text=ThroughHole,RightAngle|Name=Mounting Type
|RECORD=41|OwnerIndex=860|IndexInSheet=11|OwnerPartId=-1|Location.X=1382|Location.Y=558|Color=8388608|FontID=1|IsHidden=T|Text=-|Name=Cable Group
|RECORD=41|OwnerIndex=860|IndexInSheet=12|OwnerPartId=-1|Location.X=1382|Location.Y=558|Color=8388608|FontID=1|IsHidden=T|Text=901-143-6RFXMountingHole|Name=Catalog Drawings
|RECORD=41|OwnerIndex=860|IndexInSheet=13|OwnerPartId=-1|Location.X=1382|Location.Y=558|Color=8388608|FontID=1|IsHidden=T|Text=901-143-6RFX.igs|Name=3D Model
|RECORD=41|OwnerIndex=860|IndexInSheet=14|OwnerPartId=-1|Location.X=1382|Location.Y=558|Color=8388608|FontID=1|IsHidden=T|Text=-|Name=Series
|RECORD=41|OwnerIndex=860|IndexInSheet=15|OwnerPartId=-1|Location.X=1382|Location.Y=558|Color=8388608|FontID=1|IsHidden=T|Text=5-Pin Through Hole Device, Body 7 x 7 mm, Pitch 2.54 mm|Name=Package Description
|RECORD=41|OwnerIndex=860|IndexInSheet=16|OwnerPartId=-1|Location.X=1382|Location.Y=558|Color=8388608|FontID=1|IsHidden=T|Text=901-143-6RFX|Name=Package Reference
|RECORD=41|OwnerIndex=860|IndexInSheet=17|OwnerPartId=-1|Location.X=1382|Location.Y=558|Color=8388608|FontID=1|IsHidden=T|Text=Brass|Name=Body Material
|RECORD=41|OwnerIndex=860|IndexInSheet=18|OwnerPartId=-1|Location.X=1382|Location.Y=558|Color=8388608|FontID=1|IsHidden=T|Text=-|Name=Voltage Rating
|RECORD=41|OwnerIndex=860|IndexInSheet=19|OwnerPartId=-1|Location.X=1382|Location.Y=558|Color=8388608|FontID=1|IsHidden=T|Text=1|Name=Standard Package
|RECORD=41|OwnerIndex=860|IndexInSheet=20|OwnerPartId=-1|Location.X=1382|Location.Y=558|Color=8388608|FontID=1|IsHidden=T|Text=Jack,FemaleSocket|Name=Connector Type
|RECORD=41|OwnerIndex=860|IndexInSheet=21|OwnerPartId=-1|Location.X=1382|Location.Y=558|Color=8388608|FontID=1|IsHidden=T|Text=Threaded|Name=Fastening Type
|RECORD=41|OwnerIndex=860|IndexInSheet=22|OwnerPartId=-1|Location.X=1382|Location.Y=558|Color=8388608|FontID=1|IsHidden=T|Text=Gold|Name=Housing Color
|RECORD=41|OwnerIndex=860|IndexInSheet=23|OwnerPartId=-1|Location.X=1382|Location.Y=558|Color=8388608|FontID=1|IsHidden=T|Text=Solder|Name=Shield Termination
|RECORD=41|OwnerIndex=860|IndexInSheet=24|OwnerPartId=-1|Location.X=1382|Location.Y=558|Color=8388608|FontID=1|IsHidden=T|Text=901-143-6-RFX9011436RFXARFX1232|Name=Other Names
|RECORD=41|OwnerIndex=860|IndexInSheet=25|OwnerPartId=-1|Location.X=1382|Location.Y=558|Color=8388608|FontID=7|IsHidden=T|Text=http://www.amphenolrf.com/downloads/dl/file/id/2712/product/3102/901_143_6rfx_customer_drawing.pdf|Name=Datasheet URL
|RECORD=41|OwnerIndex=860|IndexInSheet=26|OwnerPartId=-1|Location.X=1382|Location.Y=558|Color=8388608|FontID=1|IsHidden=T|Text=CoaxialConnectors(RF)|Name=Family
|RECORD=41|OwnerIndex=860|IndexInSheet=27|OwnerPartId=-1|Location.X=1382|Location.Y=558|Color=8388608|FontID=1|IsHidden=T|Text=SMA,RFX|Name=Online Catalog
|RECORD=41|OwnerIndex=860|IndexInSheet=28|OwnerPartId=-1|Location.X=1382|Location.Y=558|Color=8388608|FontID=1|IsHidden=T|Text=18GHz|Name=Frequency - Max
|RECORD=41|OwnerIndex=860|IndexInSheet=29|OwnerPartId=-1|Location.X=1382|Location.Y=558|Color=8388608|FontID=1|IsHidden=T|Text=Solder|Name=Contact Termination
|RECORD=41|OwnerIndex=860|IndexInSheet=30|OwnerPartId=-1|Location.X=1382|Location.Y=558|Color=8388608|FontID=7|IsHidden=T|Text=http://www.amphenol.com/|Name=Manufacturer URL
|RECORD=41|OwnerIndex=860|IndexInSheet=31|OwnerPartId=-1|Location.X=1382|Location.Y=558|Color=8388608|FontID=1|IsHidden=T|Text=Amphenol|Name=Manufacturer
|RECORD=41|OwnerIndex=860|IndexInSheet=32|OwnerPartId=-1|Location.X=1382|Location.Y=558|Color=8388608|FontID=1|IsHidden=T|Text=-65°C~165°C|Name=Operating Temperature
|RECORD=41|OwnerIndex=860|IndexInSheet=33|OwnerPartId=-1|Location.X=1382|Location.Y=558|Color=8388608|FontID=1|IsHidden=T|Text=Connectors,Interconnects|Name=Category
|RECORD=41|OwnerIndex=860|IndexInSheet=34|OwnerPartId=-1|Location.X=1382|Location.Y=558|Color=8388608|FontID=1|IsHidden=T|Text=Bulk|Name=Packaging
|RECORD=41|OwnerIndex=860|IndexInSheet=35|OwnerPartId=-1|Location.X=1382|Location.Y=558|Color=8388608|FontID=1|IsHidden=T|Text=Gold|Name=Body Finish
|RECORD=41|OwnerIndex=860|IndexInSheet=36|OwnerPartId=-1|Location.X=1382|Location.Y=558|Color=8388608|FontID=1|IsHidden=T|Text=Polytetrafluoroethylene(PTFE)|Name=Dielectric Material
|RECORD=41|OwnerIndex=860|IndexInSheet=37|OwnerPartId=-1|Location.X=1382|Location.Y=558|Color=8388608|FontID=1|IsHidden=T|Text=BerylliumCopper|Name=Center Contact Material
|RECORD=41|OwnerIndex=860|IndexInSheet=38|OwnerPartId=-1|Location.X=1382|Location.Y=558|Color=8388608|FontID=1|IsHidden=T|Text=50Ohm|Name=Impedance
|RECORD=41|OwnerIndex=860|IndexInSheet=39|OwnerPartId=-1|Location.X=1382|Location.Y=558|Color=8388608|FontID=1|IsHidden=T|Text=-|Name=Features
|RECORD=41|OwnerIndex=860|IndexInSheet=40|OwnerPartId=-1|Location.X=1382|Location.Y=558|Color=8388608|FontID=1|IsHidden=T|Text=SMA|Name=Connector Style
|RECORD=41|OwnerIndex=860|IndexInSheet=41|OwnerPartId=-1|Location.X=1382|Location.Y=558|Color=8388608|FontID=1|IsHidden=T|Text=Gold|Name=Center Contact Plating
|RECORD=41|OwnerIndex=860|IndexInSheet=42|OwnerPartId=-1|Location.X=1382|Location.Y=558|Color=8388608|FontID=1|IsHidden=T|Text=Rev. C, 06/2010|Name=Datasheet Version
|RECORD=41|OwnerIndex=860|IndexInSheet=43|OwnerPartId=-1|Location.X=1382|Location.Y=558|Color=8388608|FontID=1|IsHidden=T|Text=-|Name=Ingress Protection
|RECORD=34|OwnerIndex=860|IndexInSheet=-1|OwnerPartId=-1|Location.X=1393|Location.Y=558|Color=8388608|FontID=1|Text=AN4|Name=Designator|ReadOnlyState=1
|RECORD=41|OwnerIndex=860|IndexInSheet=-1|OwnerPartId=-1|Location.X=1444|Location.Y=507|Color=8388608|FontID=1|Text=RF2-49B-T-00-50-G-HDW|Name=Comment
|RECORD=44|OwnerIndex=860
|RECORD=45|OwnerIndex=912|IndexInSheet=-1|Description=THD, 5-Leads, Body 7x7mm, Pitch 2.54mm|UseComponentLibrary=T|ModelName=AMPH-901-143-6RFX_V|ModelType=PCBLIB|DatafileCount=1|ModelDatafileEntity0=AMPH-901-143-6RFX_V|ModelDatafileKind0=PCBLib|IsCurrent=T|DatalinksLocked=T|DatabaseDatalinksLocked=T
|RECORD=46|OwnerIndex=913
|RECORD=48|OwnerIndex=913
|RECORD=41|OwnerIndex=915|IndexInSheet=-1|OwnerPartId=-1|Color=8388608|FontID=1|Text=2D|Name=Available Preview Images
|RECORD=17|IndexInSheet=70|OwnerPartId=-1|Style=4|ShowNetName=T|Location.X=1464|Location.Y=577|Orientation=3|Color=128|FontID=1|Text=GND
|RECORD=1|LibReference=RES-2|ComponentDescription=General Purpose Chip Resistor, 49.9 Ohm, +/- 1%, -55 to 155 degC, 0603 (1608 Metric), RoHS, Tape and Reel|PartCount=2|DisplayModeCount=1|IndexInSheet=71|OwnerPartId=-1|Location.X=1299|Location.Y=617|CurrentPartId=1|LibraryPath=*|SourceLibraryName=Altium Content Vault|TargetFileName=*|AreaColor=11599871|Color=128|PartIDLocked=T|DesignItemId=CMP-1659-00036-1|AllPinCount=2
|RECORD=2|OwnerIndex=918|OwnerPartId=1|FormalType=1|Electrical=4|PinConglomerate=32|PinLength=10|Location.X=1319|Location.Y=617|Name=2|Designator=2|PinPropagationDelay=0.000000E+000
|RECORD=2|OwnerIndex=918|OwnerPartId=1|FormalType=1|Electrical=4|PinConglomerate=34|PinLength=10|Location.X=1299|Location.Y=617|Name=1|Designator=1|PinPropagationDelay=0.000000E+000
|RECORD=6|OwnerIndex=918|IsNotAccesible=T|IndexInSheet=2|OwnerPartId=1|LineWidth=1|Color=16711680|LocationCount=10|X1=1319|Y1=617|X2=1315|Y2=617|X3=1314|Y3=615|X4=1312|Y4=619|X5=1310|Y5=615|X6=1308|Y6=619|X7=1306|Y7=615|X8=1304|Y8=619|X9=1303|Y9=617|X10=1299|Y10=617
|RECORD=41|OwnerIndex=918|IndexInSheet=3|OwnerPartId=-1|Location.X=1287|Location.Y=632|Color=8388608|FontID=1|IsHidden=T|Text=0603|Name=PackageReference
|RECORD=41|OwnerIndex=918|IndexInSheet=4|OwnerPartId=-1|Location.X=1287|Location.Y=632|Color=8388608|FontID=1|IsHidden=T|Text=Tray|Name=Packaging
|RECORD=41|OwnerIndex=918|IndexInSheet=5|OwnerPartId=-1|Location.X=1287|Location.Y=632|Color=8388608|FontID=1|IsHidden=T|Text=Datasheet|Name=ComponentLink2Description
|RECORD=41|OwnerIndex=918|IndexInSheet=6|OwnerPartId=-1|Location.X=1287|Location.Y=632|Color=8388608|FontID=1|IsHidden=T|Text=Manufacturer URL|Name=ComponentLink1Description
|RECORD=41|OwnerIndex=918|IndexInSheet=7|OwnerPartId=-1|Location.X=1287|Location.Y=632|Color=8388608|FontID=7|IsHidden=T|Text=https://datasheet.ciiva.com/11808/0900766b80f96399-11808223.pdf|Name=ComponentLink2URL
|RECORD=41|OwnerIndex=918|IndexInSheet=8|OwnerPartId=-1|Location.X=1287|Location.Y=632|Color=8388608|FontID=1|IsHidden=T|Text=true|Name=RoHSCompliant
|RECORD=41|OwnerIndex=918|IndexInSheet=9|OwnerPartId=-1|Location.X=1287|Location.Y=632|Color=8388608|FontID=1|IsHidden=T|Text=85 degC|Name=Max Operating Temperature
|RECORD=41|OwnerIndex=918|IndexInSheet=10|OwnerPartId=-1|Location.X=1287|Location.Y=632|Color=8388608|FontID=1|IsHidden=T|Text=3.63 V|Name=Max Supply Voltage
|RECORD=41|OwnerIndex=918|IndexInSheet=11|OwnerPartId=-1|Location.X=1287|Location.Y=632|Color=8388608|FontID=7|IsHidden=T|Text=http://www.yageo.com/|Name=ComponentLink1URL
|RECORD=41|OwnerIndex=918|IndexInSheet=12|OwnerPartId=-1|Location.X=1287|Location.Y=632|Color=8388608|FontID=1|IsHidden=T|Text=2-Pin Surface Mount Device, Body 1.6 x 0.8 mm|Name=PackageDescription
|RECORD=41|OwnerIndex=918|IndexInSheet=13|OwnerPartId=-1|Location.X=1287|Location.Y=632|Color=8388608|FontID=1|IsHidden=T|Text=LQFP|Name=Case\Package
|RECORD=41|OwnerIndex=918|IndexInSheet=14|OwnerPartId=-1|Location.X=1287|Location.Y=632|Color=8388608|FontID=1|IsHidden=T|Text=Rev. 4, 04/2009|Name=DatasheetVersion
|RECORD=41|OwnerIndex=918|IndexInSheet=15|OwnerPartId=-1|Location.X=1287|Location.Y=632|Color=8388608|FontID=1|IsHidden=T|Text=-40 degC|Name=Min Operating Temperature
|RECORD=41|OwnerIndex=918|IndexInSheet=16|OwnerPartId=-1|Location.X=1287|Location.Y=632|Color=8388608|FontID=1|IsHidden=T|Text=SPI|Name=Interface
|RECORD=41|OwnerIndex=918|IndexInSheet=17|OwnerPartId=-1|Location.X=1287|Location.Y=632|Color=8388608|FontID=1|IsHidden=T|Text=250|Name=Package Quantity
|RECORD=41|OwnerIndex=918|IndexInSheet=18|OwnerPartId=-1|Location.X=1287|Location.Y=632|Color=8388608|FontID=1|IsHidden=T|Text=2.97 V|Name=Min Supply Voltage
|RECORD=41|OwnerIndex=918|IndexInSheet=19|OwnerPartId=-1|Location.X=1287|Location.Y=632|Color=8388608|FontID=1|IsHidden=T|Text=48|Name=Pins
|RECORD=34|OwnerIndex=918|IndexInSheet=-1|OwnerPartId=-1|Location.X=1298|Location.Y=620|Color=8388608|FontID=1|Text=R34|Name=Designator|ReadOnlyState=1
|RECORD=41|OwnerIndex=918|IndexInSheet=-1|OwnerPartId=-1|Location.X=1298|Location.Y=604|Color=8388608|FontID=1|Text=49.9R|Name=Comment
|RECORD=44|OwnerIndex=918
|RECORD=45|OwnerIndex=943|IndexInSheet=-1|Description=Chip Resistor, 2-Leads, Body 1.70x0.90mm, IPC Medium Density|UseComponentLibrary=T|ModelName=RESC1608X55X25NL10T15|ModelType=PCBLIB|DatafileCount=1|ModelDatafileEntity0=RESC1608X55X25NL10T15|ModelDatafileKind0=PCBLib|IsCurrent=T|DatalinksLocked=T|DatabaseDatalinksLocked=T
|RECORD=46|OwnerIndex=944
|RECORD=48|OwnerIndex=944
|RECORD=41|OwnerIndex=946|IndexInSheet=-1|OwnerPartId=-1|Color=8388608|FontID=1|IsHidden=T|Text=2D|Name=Available Preview Images
|RECORD=45|OwnerIndex=943|IndexInSheet=-1|Description=Chip Resistor, 2-Leads, Body 1.70x0.90mm, IPC Low Density|UseComponentLibrary=T|ModelName=RESC1608X55X25ML10T15|ModelType=PCBLIB|DatafileCount=1|ModelDatafileEntity0=RESC1608X55X25ML10T15|ModelDatafileKind0=PCBLib|DatalinksLocked=T|DatabaseDatalinksLocked=T
|RECORD=46|OwnerIndex=948
|RECORD=48|OwnerIndex=948
|RECORD=41|OwnerIndex=950|IndexInSheet=-1|OwnerPartId=-1|Color=8388608|FontID=1|IsHidden=T|Text=2D|Name=Available Preview Images
|RECORD=45|OwnerIndex=943|IndexInSheet=-1|Description=Chip Resistor, 2-Leads, Body 1.70x0.90mm, IPC High Density|UseComponentLibrary=T|ModelName=RESC1608X55X25LL10T15|ModelType=PCBLIB|DatafileCount=1|ModelDatafileEntity0=RESC1608X55X25LL10T15|ModelDatafileKind0=PCBLib|DatalinksLocked=T|DatabaseDatalinksLocked=T
|RECORD=46|OwnerIndex=952
|RECORD=48|OwnerIndex=952
|RECORD=41|OwnerIndex=954|IndexInSheet=-1|OwnerPartId=-1|Color=8388608|FontID=1|IsHidden=T|Text=2D|Name=Available Preview Images
|RECORD=17|IndexInSheet=72|OwnerPartId=-1|ShowNetName=T|Location.X=1024|Location.Y=617|Orientation=2|Color=255|FontID=1|Text=ANT4_OUT|IsCrossSheetConnector=T
|RECORD=41|OwnerIndex=956|OwnerPartId=-1|Location.X=962|Location.X_Frac=7849|Location.Y=617|Orientation=2|Justification=3|Color=8388608|FontID=1|Text=FPGA[4A]|Name=CrossRef|ReadOnlyState=3
|RECORD=1|LibReference=RES-2|ComponentDescription=Precision Thick Film Chip Resistor, 4.7 KOhm, +/- 1%, -55 to 155 degC, 0603 (1608 Metric), RoHS, Tape and Reel ERJ-3EKF4701V|PartCount=2|DisplayModeCount=1|IndexInSheet=73|OwnerPartId=-1|Location.X=1034|Location.Y=677|Orientation=1|CurrentPartId=1|LibraryPath=*|SourceLibraryName=Altium Content Vault|TargetFileName=*|AreaColor=11599871|Color=128|PartIDLocked=T|DesignItemId=CMP-1012-00586-3|AllPinCount=2
|RECORD=2|OwnerIndex=958|OwnerPartId=1|FormalType=1|Electrical=4|PinConglomerate=33|PinLength=10|Location.X=1034|Location.Y=697|Name=2|Designator=2|PinPropagationDelay=0.000000E+000
|RECORD=2|OwnerIndex=958|OwnerPartId=1|FormalType=1|Electrical=4|PinConglomerate=35|PinLength=10|Location.X=1034|Location.Y=677|Name=1|Designator=1|PinPropagationDelay=0.000000E+000
|RECORD=6|OwnerIndex=958|IsNotAccesible=T|IndexInSheet=2|OwnerPartId=1|LineWidth=1|Color=16711680|LocationCount=10|X1=1034|Y1=697|X2=1034|Y2=693|X3=1036|Y3=692|X4=1032|Y4=690|X5=1036|Y5=688|X6=1032|Y6=686|X7=1036|Y7=684|X8=1032|Y8=682|X9=1034|Y9=681|X10=1034|Y10=677
|RECORD=41|OwnerIndex=958|IndexInSheet=3|OwnerPartId=-1|Location.X=1031|Location.Y=709|Color=8388608|FontID=1|IsHidden=T|Text=220 Ohm|Name=Resistance
|RECORD=41|OwnerIndex=958|IndexInSheet=4|OwnerPartId=-1|Location.X=1031|Location.Y=709|Color=8388608|FontID=1|IsHidden=T|Text=0603|Name=PackageReference
|RECORD=41|OwnerIndex=958|IndexInSheet=5|OwnerPartId=-1|Location.X=1031|Location.Y=709|Color=8388608|FontID=1|IsHidden=T|Text=50 V|Name=Voltage Rating
|RECORD=41|OwnerIndex=958|IndexInSheet=6|OwnerPartId=-1|Location.X=1031|Location.Y=709|Color=8388608|FontID=1|IsHidden=T|Text=125 degC|Name=Max Operating Temperature
|RECORD=41|OwnerIndex=958|IndexInSheet=7|OwnerPartId=-1|Location.X=1031|Location.Y=709|Color=8388608|FontID=1|IsHidden=T|Text=4|Name=Elements
|RECORD=41|OwnerIndex=958|IndexInSheet=8|OwnerPartId=-1|Location.X=1031|Location.Y=709|Color=8388608|FontID=1|IsHidden=T|Text=No SVHC|Name=REACH SVHC
|RECORD=41|OwnerIndex=958|IndexInSheet=9|OwnerPartId=-1|Location.X=1031|Location.Y=709|Color=8388608|FontID=1|IsHidden=T|Text=0.063 inch|Name=Width
|RECORD=41|OwnerIndex=958|IndexInSheet=10|OwnerPartId=-1|Location.X=1031|Location.Y=709|Color=8388608|FontID=1|IsHidden=T|Text=1205|Name=Case\Package
|RECORD=41|OwnerIndex=958|IndexInSheet=11|OwnerPartId=-1|Location.X=1031|Location.Y=709|Color=8388608|FontID=1|IsHidden=T|Text=0.126 inch|Name=Length
|RECORD=41|OwnerIndex=958|IndexInSheet=12|OwnerPartId=-1|Location.X=1031|Location.Y=709|Color=8388608|FontID=1|IsHidden=T|Text=0.024 inch|Name=Height
|RECORD=41|OwnerIndex=958|IndexInSheet=13|OwnerPartId=-1|Location.X=1031|Location.Y=709|Color=8388608|FontID=1|IsHidden=T|Text=Surface Mount|Name=Mount
|RECORD=41|OwnerIndex=958|IndexInSheet=14|OwnerPartId=-1|Location.X=1031|Location.Y=709|Color=8388608|FontID=1|IsHidden=T|Text=1|Name=Package Quantity
|RECORD=41|OwnerIndex=958|IndexInSheet=15|OwnerPartId=-1|Location.X=1031|Location.Y=709|Color=8388608|FontID=1|IsHidden=T|Text=Apr-15|Name=DatasheetVersion
|RECORD=41|OwnerIndex=958|IndexInSheet=16|OwnerPartId=-1|Location.X=1031|Location.Y=709|Color=8388608|FontID=1|IsHidden=T|Text=Manufacturer URL|Name=ComponentLink1Description
|RECORD=41|OwnerIndex=958|IndexInSheet=17|OwnerPartId=-1|Location.X=1031|Location.Y=709|Color=8388608|FontID=1|IsHidden=T|Text=-55 degC|Name=Min Operating Temperature
|RECORD=41|OwnerIndex=958|IndexInSheet=18|OwnerPartId=-1|Location.X=1031|Location.Y=709|Color=8388608|FontID=1|IsHidden=T|Text=Tape and Reel|Name=Packaging
|RECORD=41|OwnerIndex=958|IndexInSheet=19|OwnerPartId=-1|Location.X=1031|Location.Y=709|Color=8388608|FontID=1|IsHidden=T|Text=No|Name=Radiation Hardening
|RECORD=41|OwnerIndex=958|IndexInSheet=20|OwnerPartId=-1|Location.X=1031|Location.Y=709|Color=8388608|FontID=7|IsHidden=T|Text=http://industrial.panasonic.com/cdbs/www-data/pdf/RDA0000/AOA0000C86.pdf|Name=ComponentLink2URL
|RECORD=41|OwnerIndex=958|IndexInSheet=21|OwnerPartId=-1|Location.X=1031|Location.Y=709|Color=8388608|FontID=1|IsHidden=T|Text=3216|Name=Case Code (Metric)
|RECORD=41|OwnerIndex=958|IndexInSheet=22|OwnerPartId=-1|Location.X=1031|Location.Y=709|Color=8388608|FontID=1|IsHidden=T|Text=8|Name=Pins
|RECORD=41|OwnerIndex=958|IndexInSheet=23|OwnerPartId=-1|Location.X=1031|Location.Y=709|Color=8388608|FontID=1|IsHidden=T|Text=1206|Name=Case Code (Imperial)
|RECORD=41|OwnerIndex=958|IndexInSheet=24|OwnerPartId=-1|Location.X=1031|Location.Y=709|Color=8388608|FontID=1|IsHidden=T|Text=Thick Film|Name=Type (Resistor)
|RECORD=41|OwnerIndex=958|IndexInSheet=25|OwnerPartId=-1|Location.X=1031|Location.Y=709|Color=8388608|FontID=1|IsHidden=T|Text=true|Name=RoHSCompliant
|RECORD=41|OwnerIndex=958|IndexInSheet=26|OwnerPartId=-1|Location.X=1031|Location.Y=709|Color=8388608|FontID=1|IsHidden=T|Text=5%|Name=Tolerance
|RECORD=41|OwnerIndex=958|IndexInSheet=27|OwnerPartId=-1|Location.X=1031|Location.Y=709|Color=8388608|FontID=1|IsHidden=T|Text=Datasheet|Name=ComponentLink2Description
|RECORD=41|OwnerIndex=958|IndexInSheet=28|OwnerPartId=-1|Location.X=1031|Location.Y=709|Color=8388608|FontID=1|IsHidden=T|Text=2-Pin Surface Mount Device, Body 1.6 x 0.85 mm|Name=PackageDescription
|RECORD=41|OwnerIndex=958|IndexInSheet=29|OwnerPartId=-1|Location.X=1031|Location.Y=709|Color=8388608|FontID=7|IsHidden=T|Text=http://www.panasonic.com/|Name=ComponentLink1URL
|RECORD=41|OwnerIndex=958|IndexInSheet=30|OwnerPartId=-1|Location.X=1031|Location.Y=709|Color=8388608|FontID=1|IsHidden=T|Text=250 mW|Name=Power Rating
|RECORD=34|OwnerIndex=958|IndexInSheet=-1|OwnerPartId=-1|Location.X=1037|Location.Y=688|Color=8388608|FontID=1|Text=R31|Name=Designator|ReadOnlyState=1
|RECORD=41|OwnerIndex=958|IndexInSheet=-1|OwnerPartId=-1|Location.X=1037|Location.Y=678|Color=8388608|FontID=1|Text=4.7K|Name=Comment
|RECORD=44|OwnerIndex=958
|RECORD=45|OwnerIndex=994|IndexInSheet=-1|Description=Chip Resistor, 2-Leads, Body 1.75x0.95mm, IPC Medium Density|UseComponentLibrary=T|ModelName=RESC1608X55X30NL15T15|ModelType=PCBLIB|DatafileCount=1|ModelDatafileEntity0=RESC1608X55X30NL15T15|ModelDatafileKind0=PCBLib|IsCurrent=T|DatalinksLocked=T|DatabaseDatalinksLocked=T
|RECORD=46|OwnerIndex=995
|RECORD=48|OwnerIndex=995
|RECORD=41|OwnerIndex=997|IndexInSheet=-1|OwnerPartId=-1|Color=8388608|FontID=1|IsHidden=T|Text=2D|Name=Available Preview Images
|RECORD=45|OwnerIndex=994|IndexInSheet=-1|Description=Chip Resistor, 2-Leads, Body 1.75x0.95mm, IPC Low Density|UseComponentLibrary=T|ModelName=RESC1608X55X30ML15T15|ModelType=PCBLIB|DatafileCount=1|ModelDatafileEntity0=RESC1608X55X30ML15T15|ModelDatafileKind0=PCBLib|DatalinksLocked=T|DatabaseDatalinksLocked=T
|RECORD=46|OwnerIndex=999
|RECORD=48|OwnerIndex=999
|RECORD=41|OwnerIndex=1001|IndexInSheet=-1|OwnerPartId=-1|Color=8388608|FontID=1|IsHidden=T|Text=2D|Name=Available Preview Images
|RECORD=45|OwnerIndex=994|IndexInSheet=-1|Description=Chip Resistor, 2-Leads, Body 1.75x0.95mm, IPC High Density|UseComponentLibrary=T|ModelName=RESC1608X55X30LL15T15|ModelType=PCBLIB|DatafileCount=1|ModelDatafileEntity0=RESC1608X55X30LL15T15|ModelDatafileKind0=PCBLib|DatalinksLocked=T|DatabaseDatalinksLocked=T
|RECORD=46|OwnerIndex=1003
|RECORD=48|OwnerIndex=1003
|RECORD=41|OwnerIndex=1005|IndexInSheet=-1|OwnerPartId=-1|Color=8388608|FontID=1|IsHidden=T|Text=2D|Name=Available Preview Images
|RECORD=1|LibReference=RES-2|ComponentDescription=Precision Thick Film Chip Resistor, 4.7 KOhm, +/- 1%, -55 to 155 degC, 0603 (1608 Metric), RoHS, Tape and Reel ERJ-3EKF4701V|PartCount=2|DisplayModeCount=1|IndexInSheet=74|OwnerPartId=-1|Location.X=1064|Location.Y=677|Orientation=1|CurrentPartId=1|LibraryPath=*|SourceLibraryName=Altium Content Vault|TargetFileName=*|AreaColor=11599871|Color=128|PartIDLocked=T|DesignItemId=CMP-1012-00586-3|AllPinCount=2
|RECORD=2|OwnerIndex=1007|OwnerPartId=1|FormalType=1|Electrical=4|PinConglomerate=33|PinLength=10|Location.X=1064|Location.Y=697|Name=2|Designator=2|PinPropagationDelay=0.000000E+000
|RECORD=2|OwnerIndex=1007|OwnerPartId=1|FormalType=1|Electrical=4|PinConglomerate=35|PinLength=10|Location.X=1064|Location.Y=677|Name=1|Designator=1|PinPropagationDelay=0.000000E+000
|RECORD=6|OwnerIndex=1007|IsNotAccesible=T|IndexInSheet=2|OwnerPartId=1|LineWidth=1|Color=16711680|LocationCount=10|X1=1064|Y1=697|X2=1064|Y2=693|X3=1066|Y3=692|X4=1062|Y4=690|X5=1066|Y5=688|X6=1062|Y6=686|X7=1066|Y7=684|X8=1062|Y8=682|X9=1064|Y9=681|X10=1064|Y10=677
|RECORD=41|OwnerIndex=1007|IndexInSheet=3|OwnerPartId=-1|Location.X=1061|Location.Y=709|Color=8388608|FontID=1|IsHidden=T|Text=220 Ohm|Name=Resistance
|RECORD=41|OwnerIndex=1007|IndexInSheet=4|OwnerPartId=-1|Location.X=1061|Location.Y=709|Color=8388608|FontID=1|IsHidden=T|Text=0603|Name=PackageReference
|RECORD=41|OwnerIndex=1007|IndexInSheet=5|OwnerPartId=-1|Location.X=1061|Location.Y=709|Color=8388608|FontID=1|IsHidden=T|Text=50 V|Name=Voltage Rating
|RECORD=41|OwnerIndex=1007|IndexInSheet=6|OwnerPartId=-1|Location.X=1061|Location.Y=709|Color=8388608|FontID=1|IsHidden=T|Text=125 degC|Name=Max Operating Temperature
|RECORD=41|OwnerIndex=1007|IndexInSheet=7|OwnerPartId=-1|Location.X=1061|Location.Y=709|Color=8388608|FontID=1|IsHidden=T|Text=4|Name=Elements
|RECORD=41|OwnerIndex=1007|IndexInSheet=8|OwnerPartId=-1|Location.X=1061|Location.Y=709|Color=8388608|FontID=1|IsHidden=T|Text=No SVHC|Name=REACH SVHC
|RECORD=41|OwnerIndex=1007|IndexInSheet=9|OwnerPartId=-1|Location.X=1061|Location.Y=709|Color=8388608|FontID=1|IsHidden=T|Text=0.063 inch|Name=Width
|RECORD=41|OwnerIndex=1007|IndexInSheet=10|OwnerPartId=-1|Location.X=1061|Location.Y=709|Color=8388608|FontID=1|IsHidden=T|Text=1205|Name=Case\Package
|RECORD=41|OwnerIndex=1007|IndexInSheet=11|OwnerPartId=-1|Location.X=1061|Location.Y=709|Color=8388608|FontID=1|IsHidden=T|Text=0.126 inch|Name=Length
|RECORD=41|OwnerIndex=1007|IndexInSheet=12|OwnerPartId=-1|Location.X=1061|Location.Y=709|Color=8388608|FontID=1|IsHidden=T|Text=0.024 inch|Name=Height
|RECORD=41|OwnerIndex=1007|IndexInSheet=13|OwnerPartId=-1|Location.X=1061|Location.Y=709|Color=8388608|FontID=1|IsHidden=T|Text=Surface Mount|Name=Mount
|RECORD=41|OwnerIndex=1007|IndexInSheet=14|OwnerPartId=-1|Location.X=1061|Location.Y=709|Color=8388608|FontID=1|IsHidden=T|Text=1|Name=Package Quantity
|RECORD=41|OwnerIndex=1007|IndexInSheet=15|OwnerPartId=-1|Location.X=1061|Location.Y=709|Color=8388608|FontID=1|IsHidden=T|Text=Apr-15|Name=DatasheetVersion
|RECORD=41|OwnerIndex=1007|IndexInSheet=16|OwnerPartId=-1|Location.X=1061|Location.Y=709|Color=8388608|FontID=1|IsHidden=T|Text=Manufacturer URL|Name=ComponentLink1Description
|RECORD=41|OwnerIndex=1007|IndexInSheet=17|OwnerPartId=-1|Location.X=1061|Location.Y=709|Color=8388608|FontID=1|IsHidden=T|Text=-55 degC|Name=Min Operating Temperature
|RECORD=41|OwnerIndex=1007|IndexInSheet=18|OwnerPartId=-1|Location.X=1061|Location.Y=709|Color=8388608|FontID=1|IsHidden=T|Text=Tape and Reel|Name=Packaging
|RECORD=41|OwnerIndex=1007|IndexInSheet=19|OwnerPartId=-1|Location.X=1061|Location.Y=709|Color=8388608|FontID=1|IsHidden=T|Text=No|Name=Radiation Hardening
|RECORD=41|OwnerIndex=1007|IndexInSheet=20|OwnerPartId=-1|Location.X=1061|Location.Y=709|Color=8388608|FontID=7|IsHidden=T|Text=http://industrial.panasonic.com/cdbs/www-data/pdf/RDA0000/AOA0000C86.pdf|Name=ComponentLink2URL
|RECORD=41|OwnerIndex=1007|IndexInSheet=21|OwnerPartId=-1|Location.X=1061|Location.Y=709|Color=8388608|FontID=1|IsHidden=T|Text=3216|Name=Case Code (Metric)
|RECORD=41|OwnerIndex=1007|IndexInSheet=22|OwnerPartId=-1|Location.X=1061|Location.Y=709|Color=8388608|FontID=1|IsHidden=T|Text=8|Name=Pins
|RECORD=41|OwnerIndex=1007|IndexInSheet=23|OwnerPartId=-1|Location.X=1061|Location.Y=709|Color=8388608|FontID=1|IsHidden=T|Text=1206|Name=Case Code (Imperial)
|RECORD=41|OwnerIndex=1007|IndexInSheet=24|OwnerPartId=-1|Location.X=1061|Location.Y=709|Color=8388608|FontID=1|IsHidden=T|Text=Thick Film|Name=Type (Resistor)
|RECORD=41|OwnerIndex=1007|IndexInSheet=25|OwnerPartId=-1|Location.X=1061|Location.Y=709|Color=8388608|FontID=1|IsHidden=T|Text=true|Name=RoHSCompliant
|RECORD=41|OwnerIndex=1007|IndexInSheet=26|OwnerPartId=-1|Location.X=1061|Location.Y=709|Color=8388608|FontID=1|IsHidden=T|Text=5%|Name=Tolerance
|RECORD=41|OwnerIndex=1007|IndexInSheet=27|OwnerPartId=-1|Location.X=1061|Location.Y=709|Color=8388608|FontID=1|IsHidden=T|Text=Datasheet|Name=ComponentLink2Description
|RECORD=41|OwnerIndex=1007|IndexInSheet=28|OwnerPartId=-1|Location.X=1061|Location.Y=709|Color=8388608|FontID=1|IsHidden=T|Text=2-Pin Surface Mount Device, Body 1.6 x 0.85 mm|Name=PackageDescription
|RECORD=41|OwnerIndex=1007|IndexInSheet=29|OwnerPartId=-1|Location.X=1061|Location.Y=709|Color=8388608|FontID=7|IsHidden=T|Text=http://www.panasonic.com/|Name=ComponentLink1URL
|RECORD=41|OwnerIndex=1007|IndexInSheet=30|OwnerPartId=-1|Location.X=1061|Location.Y=709|Color=8388608|FontID=1|IsHidden=T|Text=250 mW|Name=Power Rating
|RECORD=34|OwnerIndex=1007|IndexInSheet=-1|OwnerPartId=-1|Location.X=1067|Location.Y=688|Color=8388608|FontID=1|Text=R32|Name=Designator|ReadOnlyState=1
|RECORD=41|OwnerIndex=1007|IndexInSheet=-1|OwnerPartId=-1|Location.X=1067|Location.Y=678|Color=8388608|FontID=1|Text=4.7K|Name=Comment
|RECORD=44|OwnerIndex=1007
|RECORD=45|OwnerIndex=1043|IndexInSheet=-1|Description=Chip Resistor, 2-Leads, Body 1.75x0.95mm, IPC Medium Density|UseComponentLibrary=T|ModelName=RESC1608X55X30NL15T15|ModelType=PCBLIB|DatafileCount=1|ModelDatafileEntity0=RESC1608X55X30NL15T15|ModelDatafileKind0=PCBLib|IsCurrent=T|DatalinksLocked=T|DatabaseDatalinksLocked=T
|RECORD=46|OwnerIndex=1044
|RECORD=48|OwnerIndex=1044
|RECORD=41|OwnerIndex=1046|IndexInSheet=-1|OwnerPartId=-1|Color=8388608|FontID=1|IsHidden=T|Text=2D|Name=Available Preview Images
|RECORD=45|OwnerIndex=1043|IndexInSheet=-1|Description=Chip Resistor, 2-Leads, Body 1.75x0.95mm, IPC Low Density|UseComponentLibrary=T|ModelName=RESC1608X55X30ML15T15|ModelType=PCBLIB|DatafileCount=1|ModelDatafileEntity0=RESC1608X55X30ML15T15|ModelDatafileKind0=PCBLib|DatalinksLocked=T|DatabaseDatalinksLocked=T
|RECORD=46|OwnerIndex=1048
|RECORD=48|OwnerIndex=1048
|RECORD=41|OwnerIndex=1050|IndexInSheet=-1|OwnerPartId=-1|Color=8388608|FontID=1|IsHidden=T|Text=2D|Name=Available Preview Images
|RECORD=45|OwnerIndex=1043|IndexInSheet=-1|Description=Chip Resistor, 2-Leads, Body 1.75x0.95mm, IPC High Density|UseComponentLibrary=T|ModelName=RESC1608X55X30LL15T15|ModelType=PCBLIB|DatafileCount=1|ModelDatafileEntity0=RESC1608X55X30LL15T15|ModelDatafileKind0=PCBLib|DatalinksLocked=T|DatabaseDatalinksLocked=T
|RECORD=46|OwnerIndex=1052
|RECORD=48|OwnerIndex=1052
|RECORD=41|OwnerIndex=1054|IndexInSheet=-1|OwnerPartId=-1|Color=8388608|FontID=1|IsHidden=T|Text=2D|Name=Available Preview Images
|RECORD=17|IndexInSheet=75|OwnerPartId=-1|ShowNetName=T|Location.X=1034|Location.Y=707|Orientation=1|Color=128|FontID=1|Text=+3.3V
|RECORD=17|IndexInSheet=76|OwnerPartId=-1|ShowNetName=T|Location.X=1064|Location.Y=707|Orientation=1|Color=128|FontID=1|Text=+3.3V
|RECORD=17|IndexInSheet=77|OwnerPartId=-1|ShowNetName=T|Location.X=1024|Location.Y=562|Orientation=2|Color=255|FontID=1|Text=ANT4_IN|IsCrossSheetConnector=T
|RECORD=41|OwnerIndex=1058|OwnerPartId=-1|Location.X=971|Location.X_Frac=1146|Location.Y=562|Orientation=2|Justification=3|Color=8388608|FontID=1|Text=FPGA[5A]|Name=CrossRef|ReadOnlyState=3
|RECORD=1|LibReference=CAP|ComponentDescription=C0603X104K5RACAUTO|PartCount=2|DisplayModeCount=2|IndexInSheet=78|OwnerPartId=-1|Location.X=1104|Location.Y=517|Orientation=3|CurrentPartId=1|SourceLibraryName=Altium Content Vault|TargetFileName=*|AreaColor=11599871|Color=128|PartIDLocked=F|DesignItemId=CMP-2006-00003-1|AllPinCount=2
|RECORD=2|OwnerIndex=1060|OwnerPartId=1|OwnerPartDisplayMode=1|FormalType=1|Electrical=4|PinConglomerate=33|PinLength=10|Location.X=1094|Location.Y=517|Name=1|Designator=1|PinPropagationDelay=0.000000E+000
|RECORD=2|OwnerIndex=1060|OwnerPartId=1|OwnerPartDisplayMode=1|FormalType=1|Electrical=4|PinConglomerate=35|PinLength=10|Location.X=1094|Location.Y=507|Name=2|Designator=2|PinPropagationDelay=0.000000E+000
|RECORD=13|OwnerIndex=1060|IsNotAccesible=T|IndexInSheet=2|OwnerPartId=1|OwnerPartDisplayMode=1|Location.X=1086|Location.Y=517|Corner.X=1102|Corner.Y=517|LineWidth=1|Color=16711680
|RECORD=13|OwnerIndex=1060|IsNotAccesible=T|IndexInSheet=3|OwnerPartId=1|OwnerPartDisplayMode=1|Location.X=1094|Location.Y=513|Corner.X=1094|Corner.Y=507|LineWidth=1|Color=16711680
|RECORD=12|OwnerIndex=1060|IsNotAccesible=T|IndexInSheet=4|OwnerPartId=1|OwnerPartDisplayMode=1|Location.X=1094|Location.Y=497|Radius=16|LineWidth=1|StartAngle=61.000|EndAngle=90.000|Color=16711680
|RECORD=12|OwnerIndex=1060|IsNotAccesible=T|IndexInSheet=5|OwnerPartId=1|OwnerPartDisplayMode=1|Location.X=1094|Location.Y=497|Radius=16|LineWidth=1|StartAngle=90.000|EndAngle=119.000|Color=16711680
|RECORD=2|OwnerIndex=1060|OwnerPartId=1|FormalType=1|Electrical=4|PinConglomerate=33|PinLength=10|Location.X=1094|Location.Y=517|Name=1|Designator=1|PinPropagationDelay=0.000000E+000
|RECORD=2|OwnerIndex=1060|OwnerPartId=1|FormalType=1|Electrical=4|PinConglomerate=35|PinLength=10|Location.X=1094|Location.Y=507|Name=2|Designator=2|PinPropagationDelay=0.000000E+000
|RECORD=13|OwnerIndex=1060|IsNotAccesible=T|IndexInSheet=8|OwnerPartId=1|Location.X=1102|Location.Y=510|Corner.X=1086|Corner.Y=510|LineWidth=1|Color=16711680
|RECORD=13|OwnerIndex=1060|IsNotAccesible=T|IndexInSheet=9|OwnerPartId=1|Location.X=1086|Location.Y=514|Corner.X=1102|Corner.Y=514|LineWidth=1|Color=16711680
|RECORD=6|OwnerIndex=1060|IsNotAccesible=T|IndexInSheet=10|OwnerPartId=1|LineWidth=1|Color=16711680|LocationCount=2|X1=1094|Y1=517|X2=1094|Y2=514
|RECORD=6|OwnerIndex=1060|IsNotAccesible=T|IndexInSheet=11|OwnerPartId=1|LineWidth=1|Color=16711680|LocationCount=2|X1=1094|Y1=507|X2=1094|Y2=510
|RECORD=41|OwnerIndex=1060|IndexInSheet=12|OwnerPartId=-1|Location.X=1085|Location.Y=529|Color=8388608|FontID=1|IsHidden=T|Text=Kemet|Name=Manufacturer
|RECORD=41|OwnerIndex=1060|IndexInSheet=13|OwnerPartId=-1|Location.X=1085|Location.Y=529|Color=8388608|FontID=1|IsHidden=T|Text=C0603X104K5RACAUTO|Name=Part Number
|RECORD=34|OwnerIndex=1060|IndexInSheet=-1|OwnerPartId=-1|Location.X=1103|Location.Y=504|Color=8388608|FontID=1|Text=C29|Name=Designator|ReadOnlyState=1
|RECORD=41|OwnerIndex=1060|IndexInSheet=-1|OwnerPartId=-1|Location.X=1103|Location.Y=490|Color=8388608|FontID=1|Text=0.1uF|Name=Comment
|RECORD=44|OwnerIndex=1060
|RECORD=45|OwnerIndex=1081|IndexInSheet=-1|Description=Chip Capacitor, 2-Leads, Body 1.60x0.80mm, IPC Low Density|UseComponentLibrary=T|ModelName=CAPC1608X87X45ML20T05|ModelType=PCBLIB|DatafileCount=1|ModelDatafileEntity0=CAPC1608X87X45ML20T05|ModelDatafileKind0=PCBLib|IsCurrent=T|DatalinksLocked=T|DatabaseDatalinksLocked=T
|RECORD=46|OwnerIndex=1082
|RECORD=48|OwnerIndex=1082
|RECORD=41|OwnerIndex=1084|IndexInSheet=-1|OwnerPartId=-1|Color=8388608|FontID=1|Text=2D|Name=Available Preview Images
|RECORD=45|OwnerIndex=1081|IndexInSheet=-1|Description=Chip Capacitor, 2-Leads, Body 1.60x0.80mm, IPC High Density|UseComponentLibrary=T|ModelName=CAPC1608X87X45LL20T05|ModelType=PCBLIB|DatafileCount=1|ModelDatafileEntity0=CAPC1608X87X45LL20T05|ModelDatafileKind0=PCBLib|DatalinksLocked=T|DatabaseDatalinksLocked=T
|RECORD=46|OwnerIndex=1086
|RECORD=48|OwnerIndex=1086
|RECORD=41|OwnerIndex=1088|IndexInSheet=-1|OwnerPartId=-1|Color=8388608|FontID=1|Text=2D|Name=Available Preview Images
|RECORD=45|OwnerIndex=1081|IndexInSheet=-1|Description=Chip Capacitor, 2-Leads, Body 1.60x0.80mm, IPC Medium Density|UseComponentLibrary=T|ModelName=CAPC1608X87X45NL20T05|ModelType=PCBLIB|DatafileCount=1|ModelDatafileEntity0=CAPC1608X87X45NL20T05|ModelDatafileKind0=PCBLib|DatalinksLocked=T|DatabaseDatalinksLocked=T
|RECORD=46|OwnerIndex=1090
|RECORD=48|OwnerIndex=1090
|RECORD=41|OwnerIndex=1092|IndexInSheet=-1|OwnerPartId=-1|Color=8388608|FontID=1|Text=2D|Name=Available Preview Images
|RECORD=17|IndexInSheet=79|OwnerPartId=-1|Style=4|ShowNetName=T|Location.X=1144|Location.Y=487|Orientation=3|Color=128|FontID=1|Text=GND
|RECORD=17|IndexInSheet=80|OwnerPartId=-1|Style=4|ShowNetName=T|Location.X=1094|Location.Y=487|Orientation=3|Color=128|FontID=1|Text=GND
|RECORD=17|IndexInSheet=81|OwnerPartId=-1|ShowNetName=T|Location.X=1094|Location.Y=707|Orientation=1|Color=128|FontID=1|Text=+3.3V
|RECORD=1|LibReference=NC7WV125K8X|ComponentDescription=Integrated Circuit|PartCount=2|DisplayModeCount=1|IndexInSheet=82|OwnerPartId=-1|Location.X=394|Location.Y=552|CurrentPartId=1|LibraryPath=*|SourceLibraryName=SamacSys.SchLib|TargetFileName=*|AreaColor=11599871|Color=128|PartIDLocked=T|DesignItemId=NC7WV125K8X|AllPinCount=8
|RECORD=41|OwnerIndex=1097|OwnerPartId=-1|Location.X=394|Location.Y=552|Color=8388608|FontID=7|IsHidden=T|Text=https://www.mouser.com/datasheet/2/308/NC7WV125-1301459.pdf|Name=Datasheet Link
|RECORD=41|OwnerIndex=1097|IndexInSheet=1|OwnerPartId=-1|Location.X=394|Location.Y=552|Color=8388608|FontID=1|IsHidden=T|Text=0.9mm|Name=Height
|RECORD=41|OwnerIndex=1097|IndexInSheet=2|OwnerPartId=-1|Location.X=394|Location.Y=552|Color=8388608|FontID=1|IsHidden=T|Text=ON Semiconductor|Name=Manufacturer_Name
|RECORD=41|OwnerIndex=1097|IndexInSheet=3|OwnerPartId=-1|Location.X=394|Location.Y=552|Color=8388608|FontID=1|IsHidden=T|Text=NC7WV125K8X|Name=Manufacturer_Part_Number
|RECORD=41|OwnerIndex=1097|IndexInSheet=4|OwnerPartId=-1|Location.X=394|Location.Y=552|Color=8388608|FontID=1|IsHidden=T|Text=512-NC7WV125K8X|Name=Mouser Part Number
|RECORD=41|OwnerIndex=1097|IndexInSheet=5|OwnerPartId=-1|Location.X=394|Location.Y=552|Color=8388608|FontID=7|IsHidden=T|Text=https://www.mouser.com/Search/Refine.aspx?Keyword=512-NC7WV125K8X|Name=Mouser Price/Stock
|RECORD=41|OwnerIndex=1097|IndexInSheet=6|OwnerPartId=-1|Location.X=394|Location.Y=552|Color=8388608|FontID=1|IsHidden=T|Text=NC7WV125K8X|Name=Arrow Part Number
|RECORD=41|OwnerIndex=1097|IndexInSheet=7|OwnerPartId=-1|Location.X=394|Location.Y=552|Color=8388608|FontID=7|IsHidden=T|Text=https://www.arrow.com/en/products/nc7wv125k8x/on-semiconductor|Name=Arrow Price/Stock
|RECORD=14|OwnerIndex=1097|IsNotAccesible=T|IndexInSheet=8|OwnerPartId=1|Location.X=414|Location.Y=527|Corner.X=484|Corner.Y=652|LineWidth=1|Color=128|AreaColor=11599871|IsSolid=T
|RECORD=2|OwnerIndex=1097|OwnerPartId=1|FormalType=1|Electrical=4|PinConglomerate=58|PinLength=20|Location.X=414|Location.Y=642|Designator=1|SwapIDPart=Ž&Ž||PinPropagationDelay=0.000000E+000
|RECORD=2|OwnerIndex=1097|OwnerPartId=1|FormalType=1|Electrical=4|PinConglomerate=58|PinLength=20|Location.X=414|Location.Y=617|Designator=2|SwapIDPart=Ž&Ž||PinPropagationDelay=0.000000E+000
|RECORD=2|OwnerIndex=1097|OwnerPartId=1|FormalType=1|Electrical=4|PinConglomerate=58|PinLength=20|Location.X=414|Location.Y=562|Designator=3|SwapIDPart=Ž&Ž||PinPropagationDelay=0.000000E+000
|RECORD=2|OwnerIndex=1097|OwnerPartId=1|FormalType=1|Electrical=4|PinConglomerate=58|PinLength=20|Location.X=414|Location.Y=532|Name=GND|Designator=4|SwapIDPart=Ž&Ž||PinPropagationDelay=0.000000E+000
|RECORD=2|OwnerIndex=1097|OwnerPartId=1|FormalType=1|Electrical=4|PinConglomerate=58|PinLength=20|Location.X=414|Location.Y=542|Name=VCC|Designator=8|SwapIDPart=Ž&Ž||PinPropagationDelay=0.000000E+000
|RECORD=2|OwnerIndex=1097|OwnerPartId=1|FormalType=1|Electrical=4|PinConglomerate=58|PinLength=20|Location.X=414|Location.Y=587|Designator=7|SwapIDPart=Ž&Ž||PinPropagationDelay=0.000000E+000
|RECORD=2|OwnerIndex=1097|OwnerPartId=1|FormalType=1|Electrical=4|PinConglomerate=56|PinLength=20|Location.X=484|Location.Y=617|Designator=6|SwapIDPart=Ž&Ž||PinPropagationDelay=0.000000E+000
|RECORD=2|OwnerIndex=1097|OwnerPartId=1|FormalType=1|Electrical=4|PinConglomerate=56|PinLength=20|Location.X=484|Location.Y=562|Designator=5|SwapIDPart=Ž&Ž||PinPropagationDelay=0.000000E+000
|RECORD=6|OwnerIndex=1097|IsNotAccesible=T|IndexInSheet=17|OwnerPartId=1|LineWidth=1|Color=16711680|LocationCount=4|X1=439|Y1=627|X2=439|Y2=607|X3=459|Y3=617|X4=439|Y4=627
|RECORD=12|OwnerIndex=1097|IsNotAccesible=T|IndexInSheet=18|OwnerPartId=1|Location.X=449|Location.Y=624|Radius=1|Radius_Frac=79777|LineWidth=1|EndAngle=360.000|Color=16711680
|RECORD=6|OwnerIndex=1097|IsNotAccesible=T|IndexInSheet=19|OwnerPartId=1|LineWidth=1|Color=16711680|LocationCount=4|X1=459|Y1=572|X2=459|Y2=552|X3=439|Y3=562|X4=459|Y4=572
|RECORD=12|OwnerIndex=1097|IsNotAccesible=T|IndexInSheet=20|OwnerPartId=1|Location.X=449|Location.Y=569|Radius=1|Radius_Frac=79777|LineWidth=1|EndAngle=360.000|Color=16711680
|RECORD=6|OwnerIndex=1097|IsNotAccesible=T|IndexInSheet=21|OwnerPartId=1|LineWidth=1|Color=16711680|LocationCount=3|X1=449|Y1=571|X2=449|Y2=587|X3=414|Y3=587
|RECORD=6|OwnerIndex=1097|IsNotAccesible=T|IndexInSheet=22|OwnerPartId=1|LineWidth=1|Color=16711680|LocationCount=3|X1=449|Y1=626|X2=449|Y2=642|X3=414|Y3=642
|RECORD=6|OwnerIndex=1097|IsNotAccesible=T|IndexInSheet=23|OwnerPartId=1|LineWidth=1|Color=16711680|LocationCount=2|X1=414|Y1=617|X2=439|Y2=617
|RECORD=6|OwnerIndex=1097|IsNotAccesible=T|IndexInSheet=24|OwnerPartId=1|LineWidth=1|Color=16711680|LocationCount=2|X1=459|Y1=617|X2=484|Y2=617
|RECORD=6|OwnerIndex=1097|IsNotAccesible=T|IndexInSheet=25|OwnerPartId=1|LineWidth=1|Color=16711680|LocationCount=2|X1=459|Y1=562|X2=484|Y2=562
|RECORD=6|OwnerIndex=1097|IsNotAccesible=T|IndexInSheet=26|OwnerPartId=1|LineWidth=1|Color=16711680|LocationCount=2|X1=439|Y1=562|X2=414|Y2=562
|RECORD=34|OwnerIndex=1097|IndexInSheet=-1|OwnerPartId=-1|Location.X=413|Location.Y=652|Color=8388608|FontID=1|Text=U12|Name=Designator|ReadOnlyState=1
|RECORD=41|OwnerIndex=1097|IndexInSheet=-1|OwnerPartId=-1|Location.X=413|Location.Y=517|Color=8388608|FontID=1|Text=NC7WV125K8X|Name=Comment
|RECORD=44|OwnerIndex=1097
|RECORD=45|OwnerIndex=1135|IndexInSheet=-1|ModelName=SOP50P310X90-8N|ModelType=PCBLIB|DatafileCount=1|ModelDatafile0=C:\Users\<user>\Documents\AltiumLL\SamacSys.PcbLib|ModelDatafileEntity0=SOP50P310X90-8N|ModelDatafileKind0=PCBLIB|IsCurrent=T
|RECORD=46|OwnerIndex=1136
|RECORD=48|OwnerIndex=1136
|RECORD=17|IndexInSheet=83|OwnerPartId=-1|Style=4|ShowNetName=T|Location.X=704|Location.Y=487|Orientation=3|Color=128|FontID=1|Text=GND
|RECORD=1|LibReference=CN-1P-M-RF3|ComponentDescription=Ultra Miniature Coaxial Connector Jack, 60 V, 50 Ohm, -40 to 90 degC, RoHS, Tape and Reel|PartCount=2|DisplayModeCount=1|IndexInSheet=84|OwnerPartId=-1|Location.X=634|Location.Y=637|CurrentPartId=1|LibraryPath=*|SourceLibraryName=Altium Content Vault|TargetFileName=*|AreaColor=11599871|Color=128|PartIDLocked=T|DesignItemId=CMP-2000-07505-1|AllPinCount=3
|RECORD=8|OwnerIndex=1140|IsNotAccesible=T|OwnerPartId=1|Location.X=654|Location.Y=617|Radius=20|SecondaryRadius=20|LineWidth=1|Color=16711680|AreaColor=16777215
|RECORD=8|OwnerIndex=1140|IsNotAccesible=T|IndexInSheet=1|OwnerPartId=1|Location.X=654|Location.Y=617|Radius=4|SecondaryRadius=4|LineWidth=1|Color=16711680|AreaColor=16777215
|RECORD=2|OwnerIndex=1140|OwnerPartId=1|FormalType=1|Electrical=4|PinConglomerate=51|PinLength=10|Location.X=644|Location.Y=597|Name=1|Designator=1|PinPropagationDelay=0.000000E+000
|RECORD=2|OwnerIndex=1140|OwnerPartId=1|FormalType=1|Electrical=4|PinConglomerate=50|PinLength=10|Location.X=634|Location.Y=617|Name=2|Designator=2|PinPropagationDelay=0.000000E+000
|RECORD=2|OwnerIndex=1140|OwnerPartId=1|FormalType=1|Electrical=4|PinConglomerate=51|PinLength=10|Location.X=664|Location.Y=597|Name=3|Designator=3|PinPropagationDelay=0.000000E+000
|RECORD=6|OwnerIndex=1140|IsNotAccesible=T|IndexInSheet=5|OwnerPartId=1|LineWidth=1|Color=16711680|LocationCount=5|X1=634|Y1=597|X2=634|Y2=637|X3=674|Y3=637|X4=674|Y4=597|X5=634|Y5=597
|RECORD=6|OwnerIndex=1140|IsNotAccesible=T|IndexInSheet=6|OwnerPartId=1|LineWidth=1|Color=16711680|LocationCount=2|X1=634|Y1=617|X2=650|Y2=617
|RECORD=41|OwnerIndex=1140|IndexInSheet=7|OwnerPartId=-1|Location.X=622|Location.Y=638|Color=8388608|FontID=1|IsHidden=T|Text=Straight|Name=Orientation
|RECORD=41|OwnerIndex=1140|IndexInSheet=8|OwnerPartId=-1|Location.X=622|Location.Y=638|Color=8388608|FontID=1|IsHidden=T|Text=Female|Name=Gender
|RECORD=41|OwnerIndex=1140|IndexInSheet=9|OwnerPartId=-1|Location.X=622|Location.Y=638|Color=8388608|FontID=1|IsHidden=T|Text=Vertical|Name=PCB Mounting Orientation
|RECORD=41|OwnerIndex=1140|IndexInSheet=10|OwnerPartId=-1|Location.X=622|Location.Y=638|Color=8388608|FontID=1|IsHidden=T|Text=SurfaceMount|Name=Mount
|RECORD=41|OwnerIndex=1140|IndexInSheet=11|OwnerPartId=-1|Location.X=622|Location.Y=638|Color=8388608|FontID=1|IsHidden=T|Text=3mm|Name=Length
|RECORD=41|OwnerIndex=1140|IndexInSheet=12|OwnerPartId=-1|Location.X=622|Location.Y=638|Color=8388608|FontID=1|IsHidden=T|Text=TapeandReel|Name=Packaging
|RECORD=41|OwnerIndex=1140|IndexInSheet=13|OwnerPartId=-1|Location.X=622|Location.Y=638|Color=8388608|FontID=1|IsHidden=T|Text=Jack|Name=Connector Type
|RECORD=41|OwnerIndex=1140|IndexInSheet=14|OwnerPartId=-1|Location.X=622|Location.Y=638|Color=8388608|FontID=1|IsHidden=T|Text=LeadFree|Name=Lead Free
|RECORD=41|OwnerIndex=1140|IndexInSheet=15|OwnerPartId=-1|Location.X=622|Location.Y=638|Color=8388608|FontID=1|IsHidden=T|Text=1|Name=Package Quantity
|RECORD=41|OwnerIndex=1140|IndexInSheet=16|OwnerPartId=-1|Location.X=622|Location.Y=638|Color=8388608|FontID=1|IsHidden=T|Text=SMD/SMT|Name=Termination
|RECORD=41|OwnerIndex=1140|IndexInSheet=17|OwnerPartId=-1|Location.X=622|Location.Y=638|Color=8388608|FontID=1|IsHidden=T|Text=CopperAlloy|Name=Contact Material
|RECORD=41|OwnerIndex=1140|IndexInSheet=18|OwnerPartId=-1|Location.X=622|Location.Y=638|Color=8388608|FontID=1|IsHidden=T|Text=Pull|Name=Fastening Type
|RECORD=41|OwnerIndex=1140|IndexInSheet=19|OwnerPartId=-1|Location.X=622|Location.Y=638|Color=8388608|FontID=1|IsHidden=T|Text=true|Name=RoHSCompliant
|RECORD=41|OwnerIndex=1140|IndexInSheet=20|OwnerPartId=-1|Location.X=622|Location.Y=638|Color=8388608|FontID=1|IsHidden=T|Text=LiquidCrystalPolymer|Name=Body Material
|RECORD=41|OwnerIndex=1140|IndexInSheet=21|OwnerPartId=-1|Location.X=622|Location.Y=638|Color=8388608|FontID=1|IsHidden=T|Text=SMD/SMT|Name=Case\/Package
|RECORD=41|OwnerIndex=1140|IndexInSheet=22|OwnerPartId=-1|Location.X=622|Location.Y=638|Color=8388608|FontID=1|IsHidden=T|Text=90degC|Name=Max Operating Temperature
|RECORD=41|OwnerIndex=1140|IndexInSheet=23|OwnerPartId=-1|Location.X=622|Location.Y=638|Color=8388608|FontID=1|IsHidden=T|Text=50Ohm|Name=Impedance
|RECORD=41|OwnerIndex=1140|IndexInSheet=24|OwnerPartId=-1|Location.X=622|Location.Y=638|Color=8388608|FontID=7|IsHidden=T|Text=http://www.te.com/commerce/DocumentDelivery/DDEController?Action=srchrtrv&DocNm=1909763&DocType=Customer+Drawing&DocLang=English|Name=Datasheet URL
|RECORD=41|OwnerIndex=1140|IndexInSheet=25|OwnerPartId=-1|Location.X=622|Location.Y=638|Color=8388608|FontID=1|IsHidden=T|Text=Gold|Name=Contact Plating
|RECORD=41|OwnerIndex=1140|IndexInSheet=26|OwnerPartId=-1|Location.X=622|Location.Y=638|Color=8388608|FontID=1|IsHidden=T|Text=SurfaceMount|Name=Mounting Technology
|RECORD=41|OwnerIndex=1140|IndexInSheet=27|OwnerPartId=-1|Location.X=622|Location.Y=638|Color=8388608|FontID=1|IsHidden=T|Text=6GHz|Name=Max Frequency
|RECORD=41|OwnerIndex=1140|IndexInSheet=28|OwnerPartId=-1|Location.X=622|Location.Y=638|Color=8388608|FontID=1|IsHidden=T|Text=TECO-1909763-1|Name=Package Reference
|RECORD=41|OwnerIndex=1140|IndexInSheet=29|OwnerPartId=-1|Location.X=622|Location.Y=638|Color=8388608|FontID=1|IsHidden=T|Text=Thermoplastic|Name=Insulation Material
|RECORD=41|OwnerIndex=1140|IndexInSheet=30|OwnerPartId=-1|Location.X=622|Location.Y=638|Color=8388608|FontID=1|IsHidden=T|Text=-40degC|Name=Min Operating Temperature
|RECORD=41|OwnerIndex=1140|IndexInSheet=31|OwnerPartId=-1|Location.X=622|Location.Y=638|Color=8388608|FontID=7|IsHidden=T|Text=http://www.te.com/|Name=Manufacturer URL
|RECORD=41|OwnerIndex=1140|IndexInSheet=32|OwnerPartId=-1|Location.X=622|Location.Y=638|Color=8388608|FontID=1|IsHidden=T|Text=Gold|Name=Body Plating
|RECORD=41|OwnerIndex=1140|IndexInSheet=33|OwnerPartId=-1|Location.X=622|Location.Y=638|Color=8388608|FontID=1|IsHidden=T|Text=Polymer|Name=Dielectric Material
|RECORD=41|OwnerIndex=1140|IndexInSheet=34|OwnerPartId=-1|Location.X=622|Location.Y=638|Color=8388608|FontID=1|IsHidden=T|Text=TE Connectivity|Name=Manufacturer
|RECORD=41|OwnerIndex=1140|IndexInSheet=35|OwnerPartId=-1|Location.X=622|Location.Y=638|Color=8388608|FontID=1|IsHidden=T|Text=Compliant|Name=ELV
|RECORD=41|OwnerIndex=1140|IndexInSheet=36|OwnerPartId=-1|Location.X=622|Location.Y=638|Color=8388608|FontID=1|IsHidden=T|Text=Rev. B2, 11/2015|Name=Datasheet Version
|RECORD=41|OwnerIndex=1140|IndexInSheet=37|OwnerPartId=-1|Location.X=622|Location.Y=638|Color=8388608|FontID=1|IsHidden=T|Text=No|Name=Radiation Hardening
|RECORD=41|OwnerIndex=1140|IndexInSheet=38|OwnerPartId=-1|Location.X=622|Location.Y=638|Color=8388608|FontID=1|IsHidden=T|Text=3-Pin Surface Mount Device, Body 2.6 x 2.6 mm|Name=Package Description
|RECORD=41|OwnerIndex=1140|IndexInSheet=39|OwnerPartId=-1|Location.X=622|Location.Y=638|Color=8388608|FontID=1|IsHidden=T|Text=Beige|Name=Housing Colour
|RECORD=34|OwnerIndex=1140|IndexInSheet=-1|OwnerPartId=-1|Location.X=633|Location.Y=638|Color=8388608|FontID=1|Text=J2|Name=Designator|ReadOnlyState=1
|RECORD=41|OwnerIndex=1140|IndexInSheet=-1|OwnerPartId=-1|Location.X=684|Location.Y=597|Color=8388608|FontID=1|Text=1909763-1|Name=Comment
|RECORD=44|OwnerIndex=1140
|RECORD=45|OwnerIndex=1186|IndexInSheet=-1|Description=SMD, 3-Leads, Body 2.6x2.6mm, Height 1.25mm|UseComponentLibrary=T|ModelName=TECO-1909763-1_V|ModelType=PCBLIB|DatafileCount=1|ModelDatafileEntity0=TECO-1909763-1_V|ModelDatafileKind0=PCBLib|IsCurrent=T|DatalinksLocked=T|DatabaseDatalinksLocked=T
|RECORD=46|OwnerIndex=1187
|RECORD=48|OwnerIndex=1187
|RECORD=41|OwnerIndex=1189|IndexInSheet=-1|OwnerPartId=-1|Color=8388608|FontID=1|Text=2D|Name=Available Preview Images
|RECORD=1|LibReference=CN-S-4F-RF5|ComponentDescription=Coaxial connector, 50 Ohm, -65 to 165 degC, 5-Pin THD, RoHS, Bulk|PartCount=2|DisplayModeCount=1|IndexInSheet=85|OwnerPartId=-1|Location.X=634|Location.Y=557|CurrentPartId=1|LibraryPath=*|SourceLibraryName=Altium Content Vault|TargetFileName=*|AreaColor=11599871|Color=128|PartIDLocked=T|DesignItemId=CMP-2000-05705-1|AllPinCount=5
|RECORD=2|OwnerIndex=1191|OwnerPartId=1|FormalType=1|Electrical=4|PinConglomerate=51|PinLength=10|Location.X=674|Location.Y=517|Name=5|Designator=5|SwapIDPart=Ž&Ž1|PinPropagationDelay=0.000000E+000
|RECORD=8|OwnerIndex=1191|IsNotAccesible=T|IndexInSheet=1|OwnerPartId=1|Location.X=654|Location.Y=537|Radius=20|SecondaryRadius=20|LineWidth=1|Color=16711680|AreaColor=16777215
|RECORD=8|OwnerIndex=1191|IsNotAccesible=T|IndexInSheet=2|OwnerPartId=1|Location.X=654|Location.Y=537|Radius=4|SecondaryRadius=4|LineWidth=1|Color=16711680|AreaColor=16777215
|RECORD=2|OwnerIndex=1191|OwnerPartId=1|FormalType=1|Electrical=4|PinConglomerate=50|PinLength=10|Location.X=634|Location.Y=537|Name=1|Designator=1|PinPropagationDelay=0.000000E+000
|RECORD=2|OwnerIndex=1191|OwnerPartId=1|FormalType=1|Electrical=4|PinConglomerate=51|PinLength=10|Location.X=644|Location.Y=517|Name=2|Designator=2|PinPropagationDelay=0.000000E+000
|RECORD=2|OwnerIndex=1191|OwnerPartId=1|FormalType=1|Electrical=4|PinConglomerate=51|PinLength=10|Location.X=654|Location.Y=517|Name=3|Designator=3|PinPropagationDelay=0.000000E+000
|RECORD=2|OwnerIndex=1191|OwnerPartId=1|FormalType=1|Electrical=4|PinConglomerate=51|PinLength=10|Location.X=664|Location.Y=517|Name=4|Designator=4|PinPropagationDelay=0.000000E+000
|RECORD=6|OwnerIndex=1191|IsNotAccesible=T|IndexInSheet=7|OwnerPartId=1|LineWidth=1|Color=16711680|LocationCount=5|X1=634|Y1=517|X2=634|Y2=557|X3=674|Y3=557|X4=674|Y4=517|X5=634|Y5=517
|RECORD=6|OwnerIndex=1191|IsNotAccesible=T|IndexInSheet=8|OwnerPartId=1|LineWidth=1|Color=16711680|LocationCount=2|X1=634|Y1=537|X2=650|Y2=537
|RECORD=41|OwnerIndex=1191|IndexInSheet=9|OwnerPartId=-1|Location.X=622|Location.Y=558|Color=8388608|FontID=1|IsHidden=T|Text=ThroughHole|Name=Mounting Technology
|RECORD=41|OwnerIndex=1191|IndexInSheet=10|OwnerPartId=-1|Location.X=622|Location.Y=558|Color=8388608|FontID=1|IsHidden=T|Text=ThroughHole,RightAngle|Name=Mounting Type
|RECORD=41|OwnerIndex=1191|IndexInSheet=11|OwnerPartId=-1|Location.X=622|Location.Y=558|Color=8388608|FontID=1|IsHidden=T|Text=-|Name=Cable Group
|RECORD=41|OwnerIndex=1191|IndexInSheet=12|OwnerPartId=-1|Location.X=622|Location.Y=558|Color=8388608|FontID=1|IsHidden=T|Text=901-143-6RFXMountingHole|Name=Catalog Drawings
|RECORD=41|OwnerIndex=1191|IndexInSheet=13|OwnerPartId=-1|Location.X=622|Location.Y=558|Color=8388608|FontID=1|IsHidden=T|Text=901-143-6RFX.igs|Name=3D Model
|RECORD=41|OwnerIndex=1191|IndexInSheet=14|OwnerPartId=-1|Location.X=622|Location.Y=558|Color=8388608|FontID=1|IsHidden=T|Text=-|Name=Series
|RECORD=41|OwnerIndex=1191|IndexInSheet=15|OwnerPartId=-1|Location.X=622|Location.Y=558|Color=8388608|FontID=1|IsHidden=T|Text=5-Pin Through Hole Device, Body 7 x 7 mm, Pitch 2.54 mm|Name=Package Description
|RECORD=41|OwnerIndex=1191|IndexInSheet=16|OwnerPartId=-1|Location.X=622|Location.Y=558|Color=8388608|FontID=1|IsHidden=T|Text=901-143-6RFX|Name=Package Reference
|RECORD=41|OwnerIndex=1191|IndexInSheet=17|OwnerPartId=-1|Location.X=622|Location.Y=558|Color=8388608|FontID=1|IsHidden=T|Text=Brass|Name=Body Material
|RECORD=41|OwnerIndex=1191|IndexInSheet=18|OwnerPartId=-1|Location.X=622|Location.Y=558|Color=8388608|FontID=1|IsHidden=T|Text=-|Name=Voltage Rating
|RECORD=41|OwnerIndex=1191|IndexInSheet=19|OwnerPartId=-1|Location.X=622|Location.Y=558|Color=8388608|FontID=1|IsHidden=T|Text=1|Name=Standard Package
|RECORD=41|OwnerIndex=1191|IndexInSheet=20|OwnerPartId=-1|Location.X=622|Location.Y=558|Color=8388608|FontID=1|IsHidden=T|Text=Jack,FemaleSocket|Name=Connector Type
|RECORD=41|OwnerIndex=1191|IndexInSheet=21|OwnerPartId=-1|Location.X=622|Location.Y=558|Color=8388608|FontID=1|IsHidden=T|Text=Threaded|Name=Fastening Type
|RECORD=41|OwnerIndex=1191|IndexInSheet=22|OwnerPartId=-1|Location.X=622|Location.Y=558|Color=8388608|FontID=1|IsHidden=T|Text=Gold|Name=Housing Color
|RECORD=41|OwnerIndex=1191|IndexInSheet=23|OwnerPartId=-1|Location.X=622|Location.Y=558|Color=8388608|FontID=1|IsHidden=T|Text=Solder|Name=Shield Termination
|RECORD=41|OwnerIndex=1191|IndexInSheet=24|OwnerPartId=-1|Location.X=622|Location.Y=558|Color=8388608|FontID=1|IsHidden=T|Text=901-143-6-RFX9011436RFXARFX1232|Name=Other Names
|RECORD=41|OwnerIndex=1191|IndexInSheet=25|OwnerPartId=-1|Location.X=622|Location.Y=558|Color=8388608|FontID=7|IsHidden=T|Text=http://www.amphenolrf.com/downloads/dl/file/id/2712/product/3102/901_143_6rfx_customer_drawing.pdf|Name=Datasheet URL
|RECORD=41|OwnerIndex=1191|IndexInSheet=26|OwnerPartId=-1|Location.X=622|Location.Y=558|Color=8388608|FontID=1|IsHidden=T|Text=CoaxialConnectors(RF)|Name=Family
|RECORD=41|OwnerIndex=1191|IndexInSheet=27|OwnerPartId=-1|Location.X=622|Location.Y=558|Color=8388608|FontID=1|IsHidden=T|Text=SMA,RFX|Name=Online Catalog
|RECORD=41|OwnerIndex=1191|IndexInSheet=28|OwnerPartId=-1|Location.X=622|Location.Y=558|Color=8388608|FontID=1|IsHidden=T|Text=18GHz|Name=Frequency - Max
|RECORD=41|OwnerIndex=1191|IndexInSheet=29|OwnerPartId=-1|Location.X=622|Location.Y=558|Color=8388608|FontID=1|IsHidden=T|Text=Solder|Name=Contact Termination
|RECORD=41|OwnerIndex=1191|IndexInSheet=30|OwnerPartId=-1|Location.X=622|Location.Y=558|Color=8388608|FontID=7|IsHidden=T|Text=http://www.amphenol.com/|Name=Manufacturer URL
|RECORD=41|OwnerIndex=1191|IndexInSheet=31|OwnerPartId=-1|Location.X=622|Location.Y=558|Color=8388608|FontID=1|IsHidden=T|Text=Amphenol|Name=Manufacturer
|RECORD=41|OwnerIndex=1191|IndexInSheet=32|OwnerPartId=-1|Location.X=622|Location.Y=558|Color=8388608|FontID=1|IsHidden=T|Text=-65°C~165°C|Name=Operating Temperature
|RECORD=41|OwnerIndex=1191|IndexInSheet=33|OwnerPartId=-1|Location.X=622|Location.Y=558|Color=8388608|FontID=1|IsHidden=T|Text=Connectors,Interconnects|Name=Category
|RECORD=41|OwnerIndex=1191|IndexInSheet=34|OwnerPartId=-1|Location.X=622|Location.Y=558|Color=8388608|FontID=1|IsHidden=T|Text=Bulk|Name=Packaging
|RECORD=41|OwnerIndex=1191|IndexInSheet=35|OwnerPartId=-1|Location.X=622|Location.Y=558|Color=8388608|FontID=1|IsHidden=T|Text=Gold|Name=Body Finish
|RECORD=41|OwnerIndex=1191|IndexInSheet=36|OwnerPartId=-1|Location.X=622|Location.Y=558|Color=8388608|FontID=1|IsHidden=T|Text=Polytetrafluoroethylene(PTFE)|Name=Dielectric Material
|RECORD=41|OwnerIndex=1191|IndexInSheet=37|OwnerPartId=-1|Location.X=622|Location.Y=558|Color=8388608|FontID=1|IsHidden=T|Text=BerylliumCopper|Name=Center Contact Material
|RECORD=41|OwnerIndex=1191|IndexInSheet=38|OwnerPartId=-1|Location.X=622|Location.Y=558|Color=8388608|FontID=1|IsHidden=T|Text=50Ohm|Name=Impedance
|RECORD=41|OwnerIndex=1191|IndexInSheet=39|OwnerPartId=-1|Location.X=622|Location.Y=558|Color=8388608|FontID=1|IsHidden=T|Text=-|Name=Features
|RECORD=41|OwnerIndex=1191|IndexInSheet=40|OwnerPartId=-1|Location.X=622|Location.Y=558|Color=8388608|FontID=1|IsHidden=T|Text=SMA|Name=Connector Style
|RECORD=41|OwnerIndex=1191|IndexInSheet=41|OwnerPartId=-1|Location.X=622|Location.Y=558|Color=8388608|FontID=1|IsHidden=T|Text=Gold|Name=Center Contact Plating
|RECORD=41|OwnerIndex=1191|IndexInSheet=42|OwnerPartId=-1|Location.X=622|Location.Y=558|Color=8388608|FontID=1|IsHidden=T|Text=Rev. C, 06/2010|Name=Datasheet Version
|RECORD=41|OwnerIndex=1191|IndexInSheet=43|OwnerPartId=-1|Location.X=622|Location.Y=558|Color=8388608|FontID=1|IsHidden=T|Text=-|Name=Ingress Protection
|RECORD=34|OwnerIndex=1191|IndexInSheet=-1|OwnerPartId=-1|Location.X=633|Location.Y=558|Color=8388608|FontID=1|Text=AN2|Name=Designator|ReadOnlyState=1
|RECORD=41|OwnerIndex=1191|IndexInSheet=-1|OwnerPartId=-1|Location.X=684|Location.Y=507|Color=8388608|FontID=1|Text=RF2-49B-T-00-50-G-HDW|Name=Comment
|RECORD=44|OwnerIndex=1191
|RECORD=45|OwnerIndex=1243|IndexInSheet=-1|Description=THD, 5-Leads, Body 7x7mm, Pitch 2.54mm|UseComponentLibrary=T|ModelName=AMPH-901-143-6RFX_V|ModelType=PCBLIB|DatafileCount=1|ModelDatafileEntity0=AMPH-901-143-6RFX_V|ModelDatafileKind0=PCBLib|IsCurrent=T|DatalinksLocked=T|DatabaseDatalinksLocked=T
|RECORD=46|OwnerIndex=1244
|RECORD=48|OwnerIndex=1244
|RECORD=41|OwnerIndex=1246|IndexInSheet=-1|OwnerPartId=-1|Color=8388608|FontID=1|Text=2D|Name=Available Preview Images
|RECORD=17|IndexInSheet=86|OwnerPartId=-1|Style=4|ShowNetName=T|Location.X=704|Location.Y=577|Orientation=3|Color=128|FontID=1|Text=GND
|RECORD=1|LibReference=RES-2|ComponentDescription=General Purpose Chip Resistor, 49.9 Ohm, +/- 1%, -55 to 155 degC, 0603 (1608 Metric), RoHS, Tape and Reel|PartCount=2|DisplayModeCount=1|IndexInSheet=87|OwnerPartId=-1|Location.X=539|Location.Y=617|CurrentPartId=1|LibraryPath=*|SourceLibraryName=Altium Content Vault|TargetFileName=*|AreaColor=11599871|Color=128|PartIDLocked=T|DesignItemId=CMP-1659-00036-1|AllPinCount=2
|RECORD=2|OwnerIndex=1249|OwnerPartId=1|FormalType=1|Electrical=4|PinConglomerate=32|PinLength=10|Location.X=559|Location.Y=617|Name=2|Designator=2|PinPropagationDelay=0.000000E+000
|RECORD=2|OwnerIndex=1249|OwnerPartId=1|FormalType=1|Electrical=4|PinConglomerate=34|PinLength=10|Location.X=539|Location.Y=617|Name=1|Designator=1|PinPropagationDelay=0.000000E+000
|RECORD=6|OwnerIndex=1249|IsNotAccesible=T|IndexInSheet=2|OwnerPartId=1|LineWidth=1|Color=16711680|LocationCount=10|X1=559|Y1=617|X2=555|Y2=617|X3=554|Y3=615|X4=552|Y4=619|X5=550|Y5=615|X6=548|Y6=619|X7=546|Y7=615|X8=544|Y8=619|X9=543|Y9=617|X10=539|Y10=617
|RECORD=41|OwnerIndex=1249|IndexInSheet=3|OwnerPartId=-1|Location.X=527|Location.Y=632|Color=8388608|FontID=1|IsHidden=T|Text=0603|Name=PackageReference
|RECORD=41|OwnerIndex=1249|IndexInSheet=4|OwnerPartId=-1|Location.X=527|Location.Y=632|Color=8388608|FontID=1|IsHidden=T|Text=Tray|Name=Packaging
|RECORD=41|OwnerIndex=1249|IndexInSheet=5|OwnerPartId=-1|Location.X=527|Location.Y=632|Color=8388608|FontID=1|IsHidden=T|Text=Datasheet|Name=ComponentLink2Description
|RECORD=41|OwnerIndex=1249|IndexInSheet=6|OwnerPartId=-1|Location.X=527|Location.Y=632|Color=8388608|FontID=1|IsHidden=T|Text=Manufacturer URL|Name=ComponentLink1Description
|RECORD=41|OwnerIndex=1249|IndexInSheet=7|OwnerPartId=-1|Location.X=527|Location.Y=632|Color=8388608|FontID=7|IsHidden=T|Text=https://datasheet.ciiva.com/11808/0900766b80f96399-11808223.pdf|Name=ComponentLink2URL
|RECORD=41|OwnerIndex=1249|IndexInSheet=8|OwnerPartId=-1|Location.X=527|Location.Y=632|Color=8388608|FontID=1|IsHidden=T|Text=true|Name=RoHSCompliant
|RECORD=41|OwnerIndex=1249|IndexInSheet=9|OwnerPartId=-1|Location.X=527|Location.Y=632|Color=8388608|FontID=1|IsHidden=T|Text=85 degC|Name=Max Operating Temperature
|RECORD=41|OwnerIndex=1249|IndexInSheet=10|OwnerPartId=-1|Location.X=527|Location.Y=632|Color=8388608|FontID=1|IsHidden=T|Text=3.63 V|Name=Max Supply Voltage
|RECORD=41|OwnerIndex=1249|IndexInSheet=11|OwnerPartId=-1|Location.X=527|Location.Y=632|Color=8388608|FontID=7|IsHidden=T|Text=http://www.yageo.com/|Name=ComponentLink1URL
|RECORD=41|OwnerIndex=1249|IndexInSheet=12|OwnerPartId=-1|Location.X=527|Location.Y=632|Color=8388608|FontID=1|IsHidden=T|Text=2-Pin Surface Mount Device, Body 1.6 x 0.8 mm|Name=PackageDescription
|RECORD=41|OwnerIndex=1249|IndexInSheet=13|OwnerPartId=-1|Location.X=527|Location.Y=632|Color=8388608|FontID=1|IsHidden=T|Text=LQFP|Name=Case\Package
|RECORD=41|OwnerIndex=1249|IndexInSheet=14|OwnerPartId=-1|Location.X=527|Location.Y=632|Color=8388608|FontID=1|IsHidden=T|Text=Rev. 4, 04/2009|Name=DatasheetVersion
|RECORD=41|OwnerIndex=1249|IndexInSheet=15|OwnerPartId=-1|Location.X=527|Location.Y=632|Color=8388608|FontID=1|IsHidden=T|Text=-40 degC|Name=Min Operating Temperature
|RECORD=41|OwnerIndex=1249|IndexInSheet=16|OwnerPartId=-1|Location.X=527|Location.Y=632|Color=8388608|FontID=1|IsHidden=T|Text=SPI|Name=Interface
|RECORD=41|OwnerIndex=1249|IndexInSheet=17|OwnerPartId=-1|Location.X=527|Location.Y=632|Color=8388608|FontID=1|IsHidden=T|Text=250|Name=Package Quantity
|RECORD=41|OwnerIndex=1249|IndexInSheet=18|OwnerPartId=-1|Location.X=527|Location.Y=632|Color=8388608|FontID=1|IsHidden=T|Text=2.97 V|Name=Min Supply Voltage
|RECORD=41|OwnerIndex=1249|IndexInSheet=19|OwnerPartId=-1|Location.X=527|Location.Y=632|Color=8388608|FontID=1|IsHidden=T|Text=48|Name=Pins
|RECORD=34|OwnerIndex=1249|IndexInSheet=-1|OwnerPartId=-1|Location.X=538|Location.Y=620|Color=8388608|FontID=1|Text=R33|Name=Designator|ReadOnlyState=1
|RECORD=41|OwnerIndex=1249|IndexInSheet=-1|OwnerPartId=-1|Location.X=538|Location.Y=604|Color=8388608|FontID=1|Text=49.9R|Name=Comment
|RECORD=44|OwnerIndex=1249
|RECORD=45|OwnerIndex=1274|IndexInSheet=-1|Description=Chip Resistor, 2-Leads, Body 1.70x0.90mm, IPC Medium Density|UseComponentLibrary=T|ModelName=RESC1608X55X25NL10T15|ModelType=PCBLIB|DatafileCount=1|ModelDatafileEntity0=RESC1608X55X25NL10T15|ModelDatafileKind0=PCBLib|IsCurrent=T|DatalinksLocked=T|DatabaseDatalinksLocked=T
|RECORD=46|OwnerIndex=1275
|RECORD=48|OwnerIndex=1275
|RECORD=41|OwnerIndex=1277|IndexInSheet=-1|OwnerPartId=-1|Color=8388608|FontID=1|IsHidden=T|Text=2D|Name=Available Preview Images
|RECORD=45|OwnerIndex=1274|IndexInSheet=-1|Description=Chip Resistor, 2-Leads, Body 1.70x0.90mm, IPC Low Density|UseComponentLibrary=T|ModelName=RESC1608X55X25ML10T15|ModelType=PCBLIB|DatafileCount=1|ModelDatafileEntity0=RESC1608X55X25ML10T15|ModelDatafileKind0=PCBLib|DatalinksLocked=T|DatabaseDatalinksLocked=T
|RECORD=46|OwnerIndex=1279
|RECORD=48|OwnerIndex=1279
|RECORD=41|OwnerIndex=1281|IndexInSheet=-1|OwnerPartId=-1|Color=8388608|FontID=1|IsHidden=T|Text=2D|Name=Available Preview Images
|RECORD=45|OwnerIndex=1274|IndexInSheet=-1|Description=Chip Resistor, 2-Leads, Body 1.70x0.90mm, IPC High Density|UseComponentLibrary=T|ModelName=RESC1608X55X25LL10T15|ModelType=PCBLIB|DatafileCount=1|ModelDatafileEntity0=RESC1608X55X25LL10T15|ModelDatafileKind0=PCBLib|DatalinksLocked=T|DatabaseDatalinksLocked=T
|RECORD=46|OwnerIndex=1283
|RECORD=48|OwnerIndex=1283
|RECORD=41|OwnerIndex=1285|IndexInSheet=-1|OwnerPartId=-1|Color=8388608|FontID=1|IsHidden=T|Text=2D|Name=Available Preview Images
|RECORD=17|IndexInSheet=88|OwnerPartId=-1|ShowNetName=T|Location.X=264|Location.Y=617|Orientation=2|Color=255|FontID=1|Text=ANT2_OUT|IsCrossSheetConnector=T
|RECORD=41|OwnerIndex=1287|OwnerPartId=-1|Location.X=202|Location.X_Frac=7849|Location.Y=617|Orientation=2|Justification=3|Color=8388608|FontID=1|Text=FPGA[4A]|Name=CrossRef|ReadOnlyState=3
|RECORD=1|LibReference=RES-2|ComponentDescription=Precision Thick Film Chip Resistor, 4.7 KOhm, +/- 1%, -55 to 155 degC, 0603 (1608 Metric), RoHS, Tape and Reel ERJ-3EKF4701V|PartCount=2|DisplayModeCount=1|IndexInSheet=89|OwnerPartId=-1|Location.X=274|Location.Y=677|Orientation=1|CurrentPartId=1|LibraryPath=*|SourceLibraryName=Altium Content Vault|TargetFileName=*|AreaColor=11599871|Color=128|PartIDLocked=T|DesignItemId=CMP-1012-00586-3|AllPinCount=2
|RECORD=2|OwnerIndex=1289|OwnerPartId=1|FormalType=1|Electrical=4|PinConglomerate=33|PinLength=10|Location.X=274|Location.Y=697|Name=2|Designator=2|PinPropagationDelay=0.000000E+000
|RECORD=2|OwnerIndex=1289|OwnerPartId=1|FormalType=1|Electrical=4|PinConglomerate=35|PinLength=10|Location.X=274|Location.Y=677|Name=1|Designator=1|PinPropagationDelay=0.000000E+000
|RECORD=6|OwnerIndex=1289|IsNotAccesible=T|IndexInSheet=2|OwnerPartId=1|LineWidth=1|Color=16711680|LocationCount=10|X1=274|Y1=697|X2=274|Y2=693|X3=276|Y3=692|X4=272|Y4=690|X5=276|Y5=688|X6=272|Y6=686|X7=276|Y7=684|X8=272|Y8=682|X9=274|Y9=681|X10=274|Y10=677
|RECORD=41|OwnerIndex=1289|IndexInSheet=3|OwnerPartId=-1|Location.X=271|Location.Y=709|Color=8388608|FontID=1|IsHidden=T|Text=220 Ohm|Name=Resistance
|RECORD=41|OwnerIndex=1289|IndexInSheet=4|OwnerPartId=-1|Location.X=271|Location.Y=709|Color=8388608|FontID=1|IsHidden=T|Text=0603|Name=PackageReference
|RECORD=41|OwnerIndex=1289|IndexInSheet=5|OwnerPartId=-1|Location.X=271|Location.Y=709|Color=8388608|FontID=1|IsHidden=T|Text=50 V|Name=Voltage Rating
|RECORD=41|OwnerIndex=1289|IndexInSheet=6|OwnerPartId=-1|Location.X=271|Location.Y=709|Color=8388608|FontID=1|IsHidden=T|Text=125 degC|Name=Max Operating Temperature
|RECORD=41|OwnerIndex=1289|IndexInSheet=7|OwnerPartId=-1|Location.X=271|Location.Y=709|Color=8388608|FontID=1|IsHidden=T|Text=4|Name=Elements
|RECORD=41|OwnerIndex=1289|IndexInSheet=8|OwnerPartId=-1|Location.X=271|Location.Y=709|Color=8388608|FontID=1|IsHidden=T|Text=No SVHC|Name=REACH SVHC
|RECORD=41|OwnerIndex=1289|IndexInSheet=9|OwnerPartId=-1|Location.X=271|Location.Y=709|Color=8388608|FontID=1|IsHidden=T|Text=0.063 inch|Name=Width
|RECORD=41|OwnerIndex=1289|IndexInSheet=10|OwnerPartId=-1|Location.X=271|Location.Y=709|Color=8388608|FontID=1|IsHidden=T|Text=1205|Name=Case\Package
|RECORD=41|OwnerIndex=1289|IndexInSheet=11|OwnerPartId=-1|Location.X=271|Location.Y=709|Color=8388608|FontID=1|IsHidden=T|Text=0.126 inch|Name=Length
|RECORD=41|OwnerIndex=1289|IndexInSheet=12|OwnerPartId=-1|Location.X=271|Location.Y=709|Color=8388608|FontID=1|IsHidden=T|Text=0.024 inch|Name=Height
|RECORD=41|OwnerIndex=1289|IndexInSheet=13|OwnerPartId=-1|Location.X=271|Location.Y=709|Color=8388608|FontID=1|IsHidden=T|Text=Surface Mount|Name=Mount
|RECORD=41|OwnerIndex=1289|IndexInSheet=14|OwnerPartId=-1|Location.X=271|Location.Y=709|Color=8388608|FontID=1|IsHidden=T|Text=1|Name=Package Quantity
|RECORD=41|OwnerIndex=1289|IndexInSheet=15|OwnerPartId=-1|Location.X=271|Location.Y=709|Color=8388608|FontID=1|IsHidden=T|Text=Apr-15|Name=DatasheetVersion
|RECORD=41|OwnerIndex=1289|IndexInSheet=16|OwnerPartId=-1|Location.X=271|Location.Y=709|Color=8388608|FontID=1|IsHidden=T|Text=Manufacturer URL|Name=ComponentLink1Description
|RECORD=41|OwnerIndex=1289|IndexInSheet=17|OwnerPartId=-1|Location.X=271|Location.Y=709|Color=8388608|FontID=1|IsHidden=T|Text=-55 degC|Name=Min Operating Temperature
|RECORD=41|OwnerIndex=1289|IndexInSheet=18|OwnerPartId=-1|Location.X=271|Location.Y=709|Color=8388608|FontID=1|IsHidden=T|Text=Tape and Reel|Name=Packaging
|RECORD=41|OwnerIndex=1289|IndexInSheet=19|OwnerPartId=-1|Location.X=271|Location.Y=709|Color=8388608|FontID=1|IsHidden=T|Text=No|Name=Radiation Hardening
|RECORD=41|OwnerIndex=1289|IndexInSheet=20|OwnerPartId=-1|Location.X=271|Location.Y=709|Color=8388608|FontID=7|IsHidden=T|Text=http://industrial.panasonic.com/cdbs/www-data/pdf/RDA0000/AOA0000C86.pdf|Name=ComponentLink2URL
|RECORD=41|OwnerIndex=1289|IndexInSheet=21|OwnerPartId=-1|Location.X=271|Location.Y=709|Color=8388608|FontID=1|IsHidden=T|Text=3216|Name=Case Code (Metric)
|RECORD=41|OwnerIndex=1289|IndexInSheet=22|OwnerPartId=-1|Location.X=271|Location.Y=709|Color=8388608|FontID=1|IsHidden=T|Text=8|Name=Pins
|RECORD=41|OwnerIndex=1289|IndexInSheet=23|OwnerPartId=-1|Location.X=271|Location.Y=709|Color=8388608|FontID=1|IsHidden=T|Text=1206|Name=Case Code (Imperial)
|RECORD=41|OwnerIndex=1289|IndexInSheet=24|OwnerPartId=-1|Location.X=271|Location.Y=709|Color=8388608|FontID=1|IsHidden=T|Text=Thick Film|Name=Type (Resistor)
|RECORD=41|OwnerIndex=1289|IndexInSheet=25|OwnerPartId=-1|Location.X=271|Location.Y=709|Color=8388608|FontID=1|IsHidden=T|Text=true|Name=RoHSCompliant
|RECORD=41|OwnerIndex=1289|IndexInSheet=26|OwnerPartId=-1|Location.X=271|Location.Y=709|Color=8388608|FontID=1|IsHidden=T|Text=5%|Name=Tolerance
|RECORD=41|OwnerIndex=1289|IndexInSheet=27|OwnerPartId=-1|Location.X=271|Location.Y=709|Color=8388608|FontID=1|IsHidden=T|Text=Datasheet|Name=ComponentLink2Description
|RECORD=41|OwnerIndex=1289|IndexInSheet=28|OwnerPartId=-1|Location.X=271|Location.Y=709|Color=8388608|FontID=1|IsHidden=T|Text=2-Pin Surface Mount Device, Body 1.6 x 0.85 mm|Name=PackageDescription
|RECORD=41|OwnerIndex=1289|IndexInSheet=29|OwnerPartId=-1|Location.X=271|Location.Y=709|Color=8388608|FontID=7|IsHidden=T|Text=http://www.panasonic.com/|Name=ComponentLink1URL
|RECORD=41|OwnerIndex=1289|IndexInSheet=30|OwnerPartId=-1|Location.X=271|Location.Y=709|Color=8388608|FontID=1|IsHidden=T|Text=250 mW|Name=Power Rating
|RECORD=34|OwnerIndex=1289|IndexInSheet=-1|OwnerPartId=-1|Location.X=277|Location.Y=688|Color=8388608|FontID=1|Text=R29|Name=Designator|ReadOnlyState=1
|RECORD=41|OwnerIndex=1289|IndexInSheet=-1|OwnerPartId=-1|Location.X=277|Location.Y=678|Color=8388608|FontID=1|Text=4.7K|Name=Comment
|RECORD=44|OwnerIndex=1289
|RECORD=45|OwnerIndex=1325|IndexInSheet=-1|Description=Chip Resistor, 2-Leads, Body 1.75x0.95mm, IPC Medium Density|UseComponentLibrary=T|ModelName=RESC1608X55X30NL15T15|ModelType=PCBLIB|DatafileCount=1|ModelDatafileEntity0=RESC1608X55X30NL15T15|ModelDatafileKind0=PCBLib|IsCurrent=T|DatalinksLocked=T|DatabaseDatalinksLocked=T
|RECORD=46|OwnerIndex=1326
|RECORD=48|OwnerIndex=1326
|RECORD=41|OwnerIndex=1328|IndexInSheet=-1|OwnerPartId=-1|Color=8388608|FontID=1|IsHidden=T|Text=2D|Name=Available Preview Images
|RECORD=45|OwnerIndex=1325|IndexInSheet=-1|Description=Chip Resistor, 2-Leads, Body 1.75x0.95mm, IPC Low Density|UseComponentLibrary=T|ModelName=RESC1608X55X30ML15T15|ModelType=PCBLIB|DatafileCount=1|ModelDatafileEntity0=RESC1608X55X30ML15T15|ModelDatafileKind0=PCBLib|DatalinksLocked=T|DatabaseDatalinksLocked=T
|RECORD=46|OwnerIndex=1330
|RECORD=48|OwnerIndex=1330
|RECORD=41|OwnerIndex=1332|IndexInSheet=-1|OwnerPartId=-1|Color=8388608|FontID=1|IsHidden=T|Text=2D|Name=Available Preview Images
|RECORD=45|OwnerIndex=1325|IndexInSheet=-1|Description=Chip Resistor, 2-Leads, Body 1.75x0.95mm, IPC High Density|UseComponentLibrary=T|ModelName=RESC1608X55X30LL15T15|ModelType=PCBLIB|DatafileCount=1|ModelDatafileEntity0=RESC1608X55X30LL15T15|ModelDatafileKind0=PCBLib|DatalinksLocked=T|DatabaseDatalinksLocked=T
|RECORD=46|OwnerIndex=1334
|RECORD=48|OwnerIndex=1334
|RECORD=41|OwnerIndex=1336|IndexInSheet=-1|OwnerPartId=-1|Color=8388608|FontID=1|IsHidden=T|Text=2D|Name=Available Preview Images
|RECORD=1|LibReference=RES-2|ComponentDescription=Precision Thick Film Chip Resistor, 4.7 KOhm, +/- 1%, -55 to 155 degC, 0603 (1608 Metric), RoHS, Tape and Reel ERJ-3EKF4701V|PartCount=2|DisplayModeCount=1|IndexInSheet=90|OwnerPartId=-1|Location.X=304|Location.Y=677|Orientation=1|CurrentPartId=1|LibraryPath=*|SourceLibraryName=Altium Content Vault|TargetFileName=*|AreaColor=11599871|Color=128|PartIDLocked=T|DesignItemId=CMP-1012-00586-3|AllPinCount=2
|RECORD=2|OwnerIndex=1338|OwnerPartId=1|FormalType=1|Electrical=4|PinConglomerate=33|PinLength=10|Location.X=304|Location.Y=697|Name=2|Designator=2|PinPropagationDelay=0.000000E+000
|RECORD=2|OwnerIndex=1338|OwnerPartId=1|FormalType=1|Electrical=4|PinConglomerate=35|PinLength=10|Location.X=304|Location.Y=677|Name=1|Designator=1|PinPropagationDelay=0.000000E+000
|RECORD=6|OwnerIndex=1338|IsNotAccesible=T|IndexInSheet=2|OwnerPartId=1|LineWidth=1|Color=16711680|LocationCount=10|X1=304|Y1=697|X2=304|Y2=693|X3=306|Y3=692|X4=302|Y4=690|X5=306|Y5=688|X6=302|Y6=686|X7=306|Y7=684|X8=302|Y8=682|X9=304|Y9=681|X10=304|Y10=677
|RECORD=41|OwnerIndex=1338|IndexInSheet=3|OwnerPartId=-1|Location.X=301|Location.Y=709|Color=8388608|FontID=1|IsHidden=T|Text=220 Ohm|Name=Resistance
|RECORD=41|OwnerIndex=1338|IndexInSheet=4|OwnerPartId=-1|Location.X=301|Location.Y=709|Color=8388608|FontID=1|IsHidden=T|Text=0603|Name=PackageReference
|RECORD=41|OwnerIndex=1338|IndexInSheet=5|OwnerPartId=-1|Location.X=301|Location.Y=709|Color=8388608|FontID=1|IsHidden=T|Text=50 V|Name=Voltage Rating
|RECORD=41|OwnerIndex=1338|IndexInSheet=6|OwnerPartId=-1|Location.X=301|Location.Y=709|Color=8388608|FontID=1|IsHidden=T|Text=125 degC|Name=Max Operating Temperature
|RECORD=41|OwnerIndex=1338|IndexInSheet=7|OwnerPartId=-1|Location.X=301|Location.Y=709|Color=8388608|FontID=1|IsHidden=T|Text=4|Name=Elements
|RECORD=41|OwnerIndex=1338|IndexInSheet=8|OwnerPartId=-1|Location.X=301|Location.Y=709|Color=8388608|FontID=1|IsHidden=T|Text=No SVHC|Name=REACH SVHC
|RECORD=41|OwnerIndex=1338|IndexInSheet=9|OwnerPartId=-1|Location.X=301|Location.Y=709|Color=8388608|FontID=1|IsHidden=T|Text=0.063 inch|Name=Width
|RECORD=41|OwnerIndex=1338|IndexInSheet=10|OwnerPartId=-1|Location.X=301|Location.Y=709|Color=8388608|FontID=1|IsHidden=T|Text=1205|Name=Case\Package
|RECORD=41|OwnerIndex=1338|IndexInSheet=11|OwnerPartId=-1|Location.X=301|Location.Y=709|Color=8388608|FontID=1|IsHidden=T|Text=0.126 inch|Name=Length
|RECORD=41|OwnerIndex=1338|IndexInSheet=12|OwnerPartId=-1|Location.X=301|Location.Y=709|Color=8388608|FontID=1|IsHidden=T|Text=0.024 inch|Name=Height
|RECORD=41|OwnerIndex=1338|IndexInSheet=13|OwnerPartId=-1|Location.X=301|Location.Y=709|Color=8388608|FontID=1|IsHidden=T|Text=Surface Mount|Name=Mount
|RECORD=41|OwnerIndex=1338|IndexInSheet=14|OwnerPartId=-1|Location.X=301|Location.Y=709|Color=8388608|FontID=1|IsHidden=T|Text=1|Name=Package Quantity
|RECORD=41|OwnerIndex=1338|IndexInSheet=15|OwnerPartId=-1|Location.X=301|Location.Y=709|Color=8388608|FontID=1|IsHidden=T|Text=Apr-15|Name=DatasheetVersion
|RECORD=41|OwnerIndex=1338|IndexInSheet=16|OwnerPartId=-1|Location.X=301|Location.Y=709|Color=8388608|FontID=1|IsHidden=T|Text=Manufacturer URL|Name=ComponentLink1Description
|RECORD=41|OwnerIndex=1338|IndexInSheet=17|OwnerPartId=-1|Location.X=301|Location.Y=709|Color=8388608|FontID=1|IsHidden=T|Text=-55 degC|Name=Min Operating Temperature
|RECORD=41|OwnerIndex=1338|IndexInSheet=18|OwnerPartId=-1|Location.X=301|Location.Y=709|Color=8388608|FontID=1|IsHidden=T|Text=Tape and Reel|Name=Packaging
|RECORD=41|OwnerIndex=1338|IndexInSheet=19|OwnerPartId=-1|Location.X=301|Location.Y=709|Color=8388608|FontID=1|IsHidden=T|Text=No|Name=Radiation Hardening
|RECORD=41|OwnerIndex=1338|IndexInSheet=20|OwnerPartId=-1|Location.X=301|Location.Y=709|Color=8388608|FontID=7|IsHidden=T|Text=http://industrial.panasonic.com/cdbs/www-data/pdf/RDA0000/AOA0000C86.pdf|Name=ComponentLink2URL
|RECORD=41|OwnerIndex=1338|IndexInSheet=21|OwnerPartId=-1|Location.X=301|Location.Y=709|Color=8388608|FontID=1|IsHidden=T|Text=3216|Name=Case Code (Metric)
|RECORD=41|OwnerIndex=1338|IndexInSheet=22|OwnerPartId=-1|Location.X=301|Location.Y=709|Color=8388608|FontID=1|IsHidden=T|Text=8|Name=Pins
|RECORD=41|OwnerIndex=1338|IndexInSheet=23|OwnerPartId=-1|Location.X=301|Location.Y=709|Color=8388608|FontID=1|IsHidden=T|Text=1206|Name=Case Code (Imperial)
|RECORD=41|OwnerIndex=1338|IndexInSheet=24|OwnerPartId=-1|Location.X=301|Location.Y=709|Color=8388608|FontID=1|IsHidden=T|Text=Thick Film|Name=Type (Resistor)
|RECORD=41|OwnerIndex=1338|IndexInSheet=25|OwnerPartId=-1|Location.X=301|Location.Y=709|Color=8388608|FontID=1|IsHidden=T|Text=true|Name=RoHSCompliant
|RECORD=41|OwnerIndex=1338|IndexInSheet=26|OwnerPartId=-1|Location.X=301|Location.Y=709|Color=8388608|FontID=1|IsHidden=T|Text=5%|Name=Tolerance
|RECORD=41|OwnerIndex=1338|IndexInSheet=27|OwnerPartId=-1|Location.X=301|Location.Y=709|Color=8388608|FontID=1|IsHidden=T|Text=Datasheet|Name=ComponentLink2Description
|RECORD=41|OwnerIndex=1338|IndexInSheet=28|OwnerPartId=-1|Location.X=301|Location.Y=709|Color=8388608|FontID=1|IsHidden=T|Text=2-Pin Surface Mount Device, Body 1.6 x 0.85 mm|Name=PackageDescription
|RECORD=41|OwnerIndex=1338|IndexInSheet=29|OwnerPartId=-1|Location.X=301|Location.Y=709|Color=8388608|FontID=7|IsHidden=T|Text=http://www.panasonic.com/|Name=ComponentLink1URL
|RECORD=41|OwnerIndex=1338|IndexInSheet=30|OwnerPartId=-1|Location.X=301|Location.Y=709|Color=8388608|FontID=1|IsHidden=T|Text=250 mW|Name=Power Rating
|RECORD=34|OwnerIndex=1338|IndexInSheet=-1|OwnerPartId=-1|Location.X=307|Location.Y=688|Color=8388608|FontID=1|Text=R30|Name=Designator|ReadOnlyState=1
|RECORD=41|OwnerIndex=1338|IndexInSheet=-1|OwnerPartId=-1|Location.X=307|Location.Y=678|Color=8388608|FontID=1|Text=4.7K|Name=Comment
|RECORD=44|OwnerIndex=1338
|RECORD=45|OwnerIndex=1374|IndexInSheet=-1|Description=Chip Resistor, 2-Leads, Body 1.75x0.95mm, IPC Medium Density|UseComponentLibrary=T|ModelName=RESC1608X55X30NL15T15|ModelType=PCBLIB|DatafileCount=1|ModelDatafileEntity0=RESC1608X55X30NL15T15|ModelDatafileKind0=PCBLib|IsCurrent=T|DatalinksLocked=T|DatabaseDatalinksLocked=T
|RECORD=46|OwnerIndex=1375
|RECORD=48|OwnerIndex=1375
|RECORD=41|OwnerIndex=1377|IndexInSheet=-1|OwnerPartId=-1|Color=8388608|FontID=1|IsHidden=T|Text=2D|Name=Available Preview Images
|RECORD=45|OwnerIndex=1374|IndexInSheet=-1|Description=Chip Resistor, 2-Leads, Body 1.75x0.95mm, IPC Low Density|UseComponentLibrary=T|ModelName=RESC1608X55X30ML15T15|ModelType=PCBLIB|DatafileCount=1|ModelDatafileEntity0=RESC1608X55X30ML15T15|ModelDatafileKind0=PCBLib|DatalinksLocked=T|DatabaseDatalinksLocked=T
|RECORD=46|OwnerIndex=1379
|RECORD=48|OwnerIndex=1379
|RECORD=41|OwnerIndex=1381|IndexInSheet=-1|OwnerPartId=-1|Color=8388608|FontID=1|IsHidden=T|Text=2D|Name=Available Preview Images
|RECORD=45|OwnerIndex=1374|IndexInSheet=-1|Description=Chip Resistor, 2-Leads, Body 1.75x0.95mm, IPC High Density|UseComponentLibrary=T|ModelName=RESC1608X55X30LL15T15|ModelType=PCBLIB|DatafileCount=1|ModelDatafileEntity0=RESC1608X55X30LL15T15|ModelDatafileKind0=PCBLib|DatalinksLocked=T|DatabaseDatalinksLocked=T
|RECORD=46|OwnerIndex=1383
|RECORD=48|OwnerIndex=1383
|RECORD=41|OwnerIndex=1385|IndexInSheet=-1|OwnerPartId=-1|Color=8388608|FontID=1|IsHidden=T|Text=2D|Name=Available Preview Images
|RECORD=17|IndexInSheet=91|OwnerPartId=-1|ShowNetName=T|Location.X=274|Location.Y=707|Orientation=1|Color=128|FontID=1|Text=+3.3V
|RECORD=17|IndexInSheet=92|OwnerPartId=-1|ShowNetName=T|Location.X=304|Location.Y=707|Orientation=1|Color=128|FontID=1|Text=+3.3V
|RECORD=17|IndexInSheet=93|OwnerPartId=-1|ShowNetName=T|Location.X=264|Location.Y=562|Orientation=2|Color=255|FontID=1|Text=ANT2_IN|IsCrossSheetConnector=T
|RECORD=41|OwnerIndex=1389|OwnerPartId=-1|Location.X=211|Location.X_Frac=1146|Location.Y=562|Orientation=2|Justification=3|Color=8388608|FontID=1|Text=FPGA[4A]|Name=CrossRef|ReadOnlyState=3
|RECORD=1|LibReference=CAP|ComponentDescription=C0603X104K5RACAUTO|PartCount=2|DisplayModeCount=2|IndexInSheet=94|OwnerPartId=-1|Location.X=344|Location.Y=517|Orientation=3|CurrentPartId=1|SourceLibraryName=Altium Content Vault|TargetFileName=*|AreaColor=11599871|Color=128|PartIDLocked=F|DesignItemId=CMP-2006-00003-1|AllPinCount=2
|RECORD=2|OwnerIndex=1391|OwnerPartId=1|OwnerPartDisplayMode=1|FormalType=1|Electrical=4|PinConglomerate=33|PinLength=10|Location.X=334|Location.Y=517|Name=1|Designator=1|PinPropagationDelay=0.000000E+000
|RECORD=2|OwnerIndex=1391|OwnerPartId=1|OwnerPartDisplayMode=1|FormalType=1|Electrical=4|PinConglomerate=35|PinLength=10|Location.X=334|Location.Y=507|Name=2|Designator=2|PinPropagationDelay=0.000000E+000
|RECORD=13|OwnerIndex=1391|IsNotAccesible=T|IndexInSheet=2|OwnerPartId=1|OwnerPartDisplayMode=1|Location.X=326|Location.Y=517|Corner.X=342|Corner.Y=517|LineWidth=1|Color=16711680
|RECORD=13|OwnerIndex=1391|IsNotAccesible=T|IndexInSheet=3|OwnerPartId=1|OwnerPartDisplayMode=1|Location.X=334|Location.Y=513|Corner.X=334|Corner.Y=507|LineWidth=1|Color=16711680
|RECORD=12|OwnerIndex=1391|IsNotAccesible=T|IndexInSheet=4|OwnerPartId=1|OwnerPartDisplayMode=1|Location.X=334|Location.Y=497|Radius=16|LineWidth=1|StartAngle=61.000|EndAngle=90.000|Color=16711680
|RECORD=12|OwnerIndex=1391|IsNotAccesible=T|IndexInSheet=5|OwnerPartId=1|OwnerPartDisplayMode=1|Location.X=334|Location.Y=497|Radius=16|LineWidth=1|StartAngle=90.000|EndAngle=119.000|Color=16711680
|RECORD=2|OwnerIndex=1391|OwnerPartId=1|FormalType=1|Electrical=4|PinConglomerate=33|PinLength=10|Location.X=334|Location.Y=517|Name=1|Designator=1|PinPropagationDelay=0.000000E+000
|RECORD=2|OwnerIndex=1391|OwnerPartId=1|FormalType=1|Electrical=4|PinConglomerate=35|PinLength=10|Location.X=334|Location.Y=507|Name=2|Designator=2|PinPropagationDelay=0.000000E+000
|RECORD=13|OwnerIndex=1391|IsNotAccesible=T|IndexInSheet=8|OwnerPartId=1|Location.X=342|Location.Y=510|Corner.X=326|Corner.Y=510|LineWidth=1|Color=16711680
|RECORD=13|OwnerIndex=1391|IsNotAccesible=T|IndexInSheet=9|OwnerPartId=1|Location.X=326|Location.Y=514|Corner.X=342|Corner.Y=514|LineWidth=1|Color=16711680
|RECORD=6|OwnerIndex=1391|IsNotAccesible=T|IndexInSheet=10|OwnerPartId=1|LineWidth=1|Color=16711680|LocationCount=2|X1=334|Y1=517|X2=334|Y2=514
|RECORD=6|OwnerIndex=1391|IsNotAccesible=T|IndexInSheet=11|OwnerPartId=1|LineWidth=1|Color=16711680|LocationCount=2|X1=334|Y1=507|X2=334|Y2=510
|RECORD=41|OwnerIndex=1391|IndexInSheet=12|OwnerPartId=-1|Location.X=325|Location.Y=529|Color=8388608|FontID=1|IsHidden=T|Text=Kemet|Name=Manufacturer
|RECORD=41|OwnerIndex=1391|IndexInSheet=13|OwnerPartId=-1|Location.X=325|Location.Y=529|Color=8388608|FontID=1|IsHidden=T|Text=C0603X104K5RACAUTO|Name=Part Number
|RECORD=34|OwnerIndex=1391|IndexInSheet=-1|OwnerPartId=-1|Location.X=343|Location.Y=504|Color=8388608|FontID=1|Text=C28|Name=Designator|ReadOnlyState=1
|RECORD=41|OwnerIndex=1391|IndexInSheet=-1|OwnerPartId=-1|Location.X=343|Location.Y=490|Color=8388608|FontID=1|Text=0.1uF|Name=Comment
|RECORD=44|OwnerIndex=1391
|RECORD=45|OwnerIndex=1412|IndexInSheet=-1|Description=Chip Capacitor, 2-Leads, Body 1.60x0.80mm, IPC Low Density|UseComponentLibrary=T|ModelName=CAPC1608X87X45ML20T05|ModelType=PCBLIB|DatafileCount=1|ModelDatafileEntity0=CAPC1608X87X45ML20T05|ModelDatafileKind0=PCBLib|IsCurrent=T|DatalinksLocked=T|DatabaseDatalinksLocked=T
|RECORD=46|OwnerIndex=1413
|RECORD=48|OwnerIndex=1413
|RECORD=41|OwnerIndex=1415|IndexInSheet=-1|OwnerPartId=-1|Color=8388608|FontID=1|Text=2D|Name=Available Preview Images
|RECORD=45|OwnerIndex=1412|IndexInSheet=-1|Description=Chip Capacitor, 2-Leads, Body 1.60x0.80mm, IPC High Density|UseComponentLibrary=T|ModelName=CAPC1608X87X45LL20T05|ModelType=PCBLIB|DatafileCount=1|ModelDatafileEntity0=CAPC1608X87X45LL20T05|ModelDatafileKind0=PCBLib|DatalinksLocked=T|DatabaseDatalinksLocked=T
|RECORD=46|OwnerIndex=1417
|RECORD=48|OwnerIndex=1417
|RECORD=41|OwnerIndex=1419|IndexInSheet=-1|OwnerPartId=-1|Color=8388608|FontID=1|Text=2D|Name=Available Preview Images
|RECORD=45|OwnerIndex=1412|IndexInSheet=-1|Description=Chip Capacitor, 2-Leads, Body 1.60x0.80mm, IPC Medium Density|UseComponentLibrary=T|ModelName=CAPC1608X87X45NL20T05|ModelType=PCBLIB|DatafileCount=1|ModelDatafileEntity0=CAPC1608X87X45NL20T05|ModelDatafileKind0=PCBLib|DatalinksLocked=T|DatabaseDatalinksLocked=T
|RECORD=46|OwnerIndex=1421
|RECORD=48|OwnerIndex=1421
|RECORD=41|OwnerIndex=1423|IndexInSheet=-1|OwnerPartId=-1|Color=8388608|FontID=1|Text=2D|Name=Available Preview Images
|RECORD=17|IndexInSheet=95|OwnerPartId=-1|Style=4|ShowNetName=T|Location.X=384|Location.Y=487|Orientation=3|Color=128|FontID=1|Text=GND
|RECORD=17|IndexInSheet=96|OwnerPartId=-1|Style=4|ShowNetName=T|Location.X=334|Location.Y=487|Orientation=3|Color=128|FontID=1|Text=GND
|RECORD=17|IndexInSheet=97|OwnerPartId=-1|ShowNetName=T|Location.X=334|Location.Y=707|Orientation=1|Color=128|FontID=1|Text=+3.3V
|RECORD=1|LibReference=WE-TVS-HS-4|ComponentDescription=TVS Diode WE-TVS-HS, VRWM=3.3V|PartCount=2|DisplayModeCount=1|IndexInSheet=98|OwnerPartId=-1|Location.X=1334|Location.Y=757|Orientation=1|CurrentPartId=1|LibraryPath=*|SourceLibraryName=Altium Content Vault|TargetFileName=*|AreaColor=11599871|Color=128|PartIDLocked=F|DesignItemId=CMP-1486-00002-1|AllPinCount=4
|RECORD=14|OwnerIndex=1428|IsNotAccesible=T|OwnerPartId=1|Location.X=1328|Location.Y=734|Corner.X=1368|Corner.Y=772|AreaColor=11599871|IsSolid=T|Transparent=T
|RECORD=6|OwnerIndex=1428|IsNotAccesible=T|IndexInSheet=1|OwnerPartId=1|LineWidth=1|Color=16711680|LocationCount=4|X1=1338|X1_Frac=10000|Y1=758|Y1_Frac=40000|X2=1336|X2_Frac=10000|Y2=756|Y2_Frac=40000|X3=1332|X3_Frac=10000|Y3=756|Y3_Frac=40000|X4=1330|X4_Frac=10000|Y4=754|Y4_Frac=40000
|RECORD=7|OwnerIndex=1428|IsNotAccesible=T|IndexInSheet=2|OwnerPartId=1|LineWidth=1|Color=16711680|AreaColor=16711680|IsSolid=T|LocationCount=3|X1=1338|X1_Frac=90000|Y1=750|Y1_Frac=50000|X2=1333|X2_Frac=90000|Y2=755|Y2_Frac=50000|X3=1328|X3_Frac=90000|Y3=750|Y3_Frac=50000
|RECORD=12|OwnerIndex=1428|IsNotAccesible=T|IndexInSheet=3|OwnerPartId=1|Location.X=1345|Location.Y=755|Radius_Frac=63392|LineWidth=1|StartAngle=57.394|EndAngle=30.947
|RECORD=6|OwnerIndex=1428|IsNotAccesible=T|IndexInSheet=4|OwnerPartId=1|LineWidth=1|LocationCount=2|X1=1354|Y1=755|X2=1345|Y2=755
|RECORD=7|OwnerIndex=1428|IsNotAccesible=T|IndexInSheet=5|OwnerPartId=1|LineWidth=1|Color=16711680|AreaColor=16711680|LocationCount=3|X1=1349|X1_Frac=90000|Y1=742|Y1_Frac=50000|X2=1344|X2_Frac=90000|Y2=747|Y2_Frac=50000|X3=1339|X3_Frac=90000|Y3=742|Y3_Frac=50000
|RECORD=6|OwnerIndex=1428|IsNotAccesible=T|IndexInSheet=6|OwnerPartId=1|LineWidth=1|Color=16711680|LocationCount=2|X1=1341|Y1=748|X2=1348|X2_Frac=87402|Y2=748
|RECORD=7|OwnerIndex=1428|IsNotAccesible=T|IndexInSheet=7|OwnerPartId=1|LineWidth=1|Color=16711680|AreaColor=16711680|LocationCount=3|X1=1349|X1_Frac=90000|Y1=758|Y1_Frac=50000|X2=1344|X2_Frac=90000|Y2=763|Y2_Frac=50000|X3=1339|X3_Frac=90000|Y3=758|Y3_Frac=50000
|RECORD=6|OwnerIndex=1428|IsNotAccesible=T|IndexInSheet=8|OwnerPartId=1|LineWidth=1|Color=16711680|LocationCount=2|X1=1341|Y1=764|X2=1348|X2_Frac=87402|Y2=764
|RECORD=6|OwnerIndex=1428|IsNotAccesible=T|IndexInSheet=9|OwnerPartId=1|LineWidth=1|LocationCount=2|X1=1345|Y1=748|X2=1345|Y2=758
|RECORD=6|OwnerIndex=1428|IsNotAccesible=T|IndexInSheet=10|OwnerPartId=1|LineWidth=1|LocationCount=2|X1=1345|Y1=764|X2=1345|Y2=770
|RECORD=6|OwnerIndex=1428|IsNotAccesible=T|IndexInSheet=11|OwnerPartId=1|LineWidth=1|LocationCount=2|X1=1334|Y1=757|X2=1334|Y2=770
|RECORD=6|OwnerIndex=1428|IsNotAccesible=T|IndexInSheet=12|OwnerPartId=1|LineWidth=1|LocationCount=2|X1=1334|Y1=736|X2=1334|Y2=750
|RECORD=6|OwnerIndex=1428|IsNotAccesible=T|IndexInSheet=13|OwnerPartId=1|LineWidth=1|LocationCount=2|X1=1345|Y1=736|X2=1345|Y2=742
|RECORD=6|OwnerIndex=1428|IsNotAccesible=T|IndexInSheet=14|OwnerPartId=1|LineWidth=1|LocationCount=2|X1=1334|Y1=736|X2=1362|Y2=736
|RECORD=6|OwnerIndex=1428|IsNotAccesible=T|IndexInSheet=15|OwnerPartId=1|LineWidth=1|LocationCount=2|X1=1334|Y1=770|X2=1362|Y2=770
|RECORD=6|OwnerIndex=1428|IsNotAccesible=T|IndexInSheet=16|OwnerPartId=1|LineWidth=1|LocationCount=2|X1=1354|Y1=751|X2=1354|Y2=737
|RECORD=2|OwnerIndex=1428|OwnerPartId=1|FormalType=1|Electrical=4|PinConglomerate=51|PinLength=10|Location.X=1334|Location.Y=737|Name=GND|Designator=1|PinPropagationDelay=0.000000E+000
|RECORD=2|OwnerIndex=1428|OwnerPartId=1|FormalType=1|Electrical=4|PinConglomerate=51|PinLength=10|Location.X=1354|Location.Y=737|Name=I/O1|Designator=2|PinPropagationDelay=0.000000E+000
|RECORD=2|OwnerIndex=1428|OwnerPartId=1|FormalType=1|Electrical=4|PinConglomerate=49|PinLength=10|Location.X=1354|Location.Y=767|Name=I/O2|Designator=3|PinPropagationDelay=0.000000E+000
|RECORD=2|OwnerIndex=1428|OwnerPartId=1|FormalType=1|Electrical=4|PinConglomerate=49|PinLength=10|Location.X=1334|Location.Y=767|Name=VDD|Designator=4|PinPropagationDelay=0.000000E+000
|RECORD=12|OwnerIndex=1428|IsNotAccesible=T|IndexInSheet=21|OwnerPartId=1|Location.X=1334|Location.Y=770|Radius_Frac=63392|LineWidth=1|StartAngle=57.394|EndAngle=30.947
|RECORD=12|OwnerIndex=1428|IsNotAccesible=T|IndexInSheet=22|OwnerPartId=1|Location.X=1334|Location.Y=736|Radius_Frac=63392|LineWidth=1|StartAngle=57.394|EndAngle=30.947
|RECORD=12|OwnerIndex=1428|IsNotAccesible=T|IndexInSheet=23|OwnerPartId=1|Location.X=1362|Location.Y=751|Radius_Frac=63392|LineWidth=1|StartAngle=57.394|EndAngle=30.947
|RECORD=6|OwnerIndex=1428|IsNotAccesible=T|IndexInSheet=24|OwnerPartId=1|LineWidth=1|LocationCount=2|X1=1354|Y1=751|X2=1362|Y2=751
|RECORD=7|OwnerIndex=1428|IsNotAccesible=T|IndexInSheet=25|OwnerPartId=1|LineWidth=1|Color=16711680|AreaColor=16711680|LocationCount=3|X1=1366|X1_Frac=90000|Y1=742|Y1_Frac=50000|X2=1361|X2_Frac=90000|Y2=747|Y2_Frac=50000|X3=1356|X3_Frac=90000|Y3=742|Y3_Frac=50000
|RECORD=6|OwnerIndex=1428|IsNotAccesible=T|IndexInSheet=26|OwnerPartId=1|LineWidth=1|Color=16711680|LocationCount=2|X1=1358|Y1=748|X2=1365|X2_Frac=87402|Y2=748
|RECORD=7|OwnerIndex=1428|IsNotAccesible=T|IndexInSheet=27|OwnerPartId=1|LineWidth=1|Color=16711680|AreaColor=16711680|LocationCount=3|X1=1366|X1_Frac=90000|Y1=758|Y1_Frac=50000|X2=1361|X2_Frac=90000|Y2=763|Y2_Frac=50000|X3=1356|X3_Frac=90000|Y3=758|Y3_Frac=50000
|RECORD=6|OwnerIndex=1428|IsNotAccesible=T|IndexInSheet=28|OwnerPartId=1|LineWidth=1|Color=16711680|LocationCount=2|X1=1358|Y1=764|X2=1365|X2_Frac=87402|Y2=764
|RECORD=6|OwnerIndex=1428|IsNotAccesible=T|IndexInSheet=29|OwnerPartId=1|LineWidth=1|LocationCount=2|X1=1362|Y1=748|X2=1362|Y2=758
|RECORD=6|OwnerIndex=1428|IsNotAccesible=T|IndexInSheet=30|OwnerPartId=1|LineWidth=1|LocationCount=2|X1=1362|Y1=764|X2=1362|Y2=770
|RECORD=6|OwnerIndex=1428|IsNotAccesible=T|IndexInSheet=31|OwnerPartId=1|LineWidth=1|LocationCount=2|X1=1362|Y1=736|X2=1362|Y2=742
|RECORD=12|OwnerIndex=1428|IsNotAccesible=T|IndexInSheet=32|OwnerPartId=1|Location.X=1345|Location.Y=770|Radius_Frac=63392|LineWidth=1|StartAngle=57.394|EndAngle=30.947
|RECORD=12|OwnerIndex=1428|IsNotAccesible=T|IndexInSheet=33|OwnerPartId=1|Location.X=1345|Location.Y=736|Radius_Frac=63392|LineWidth=1|StartAngle=57.394|EndAngle=30.947
|RECORD=6|OwnerIndex=1428|IsNotAccesible=T|IndexInSheet=34|OwnerPartId=1|LineWidth=1|LocationCount=2|X1=1354|Y1=755|X2=1354|Y2=772
|RECORD=41|OwnerIndex=1428|IndexInSheet=35|OwnerPartId=-1|Location.X=1327|Location.X_Frac=90000|Location.Y=779|Color=8388608|FontID=1|IsHidden=T|Text=8240136|Name=PartNumber
|RECORD=41|OwnerIndex=1428|IndexInSheet=36|OwnerPartId=-1|Location.X=1327|Location.X_Frac=90000|Location.Y=779|Color=8388608|FontID=1|IsHidden=T|Text=Manufacturer URL|Name=ComponentLink1Description
|RECORD=41|OwnerIndex=1428|IndexInSheet=37|OwnerPartId=-1|Location.X=1327|Location.X_Frac=90000|Location.Y=779|Color=8388608|FontID=1|IsHidden=T|Text=Wuerth Elektronik|Name=Manufacturer
|RECORD=41|OwnerIndex=1428|IndexInSheet=38|OwnerPartId=-1|Location.X=1327|Location.X_Frac=90000|Location.Y=779|Color=8388608|FontID=1|IsHidden=T|Text=SOT143-4L|Name=PackageReference
|RECORD=41|OwnerIndex=1428|IndexInSheet=39|OwnerPartId=-1|Location.X=1327|Location.X_Frac=90000|Location.Y=779|Color=8388608|FontID=7|IsHidden=T|Text=http://www.we-online.com|Name=ComponentLink1URL
|RECORD=41|OwnerIndex=1428|IndexInSheet=40|OwnerPartId=-1|Location.X=1327|Location.X_Frac=90000|Location.Y=779|Color=8388608|FontID=1|IsHidden=T|Text=3.3V|Name=Reverse Stand Off Voltage
|RECORD=41|OwnerIndex=1428|IndexInSheet=41|OwnerPartId=-1|Location.X=1327|Location.X_Frac=90000|Location.Y=779|Color=8388608|FontID=1|IsHidden=T|Text=Datasheet|Name=ComponentLink2Description
|RECORD=41|OwnerIndex=1428|IndexInSheet=42|OwnerPartId=-1|Location.X=1327|Location.X_Frac=90000|Location.Y=779|Color=8388608|FontID=7|IsHidden=T|Text=http://katalog.we-online.de/kataloge/eisos/media/pdf/8240136.pdf|Name=ComponentLink2URL
|RECORD=34|OwnerIndex=1428|IndexInSheet=-1|OwnerPartId=-1|Location.X=1368|Location.Y=763|Color=8388608|FontID=1|Text=D2|Name=Designator|ReadOnlyState=1
|RECORD=41|OwnerIndex=1428|IndexInSheet=-1|OwnerPartId=-1|Location.X=1368|Location.Y=753|Color=8388608|FontID=1|Text=8240136|Name=Comment
|RECORD=44|OwnerIndex=1428
|RECORD=45|OwnerIndex=1478|IndexInSheet=-1|Description=SOT143-4L, 4-Leads, Body 2.95x2.4mm, Pitch 1.70/1.90mm|UseComponentLibrary=T|ModelName=SOT143-4L|ModelType=PCBLIB|DatafileCount=1|ModelDatafileEntity0=SOT143-4L|ModelDatafileKind0=PCBLib|IsCurrent=T|DatalinksLocked=T|DatabaseDatalinksLocked=T
|RECORD=46|OwnerIndex=1479
|RECORD=48|OwnerIndex=1479
|RECORD=41|OwnerIndex=1481|IndexInSheet=-1|OwnerPartId=-1|Color=8388608|FontID=1|IsHidden=T|Text=2D|Name=Available Preview Images
|RECORD=17|IndexInSheet=99|OwnerPartId=-1|ShowNetName=T|Location.X=574|Location.Y=797|Orientation=1|Color=128|FontID=1|Text=+3.3V
|RECORD=17|IndexInSheet=100|OwnerPartId=-1|Style=4|ShowNetName=T|Location.X=574|Location.Y=707|Orientation=3|Color=128|FontID=1|Text=GND
|RECORD=17|IndexInSheet=101|OwnerPartId=-1|ShowNetName=T|Location.X=1334|Location.Y=797|Orientation=1|Color=128|FontID=1|Text=+3.3V
|RECORD=17|IndexInSheet=102|OwnerPartId=-1|Style=4|ShowNetName=T|Location.X=1334|Location.Y=707|Orientation=3|Color=128|FontID=1|Text=GND
|RECORD=4|IndexInSheet=103|OwnerPartId=-1|Location.X=727|Location.Y=1022|Color=8388608|FontID=6|Text=INPUT/OUTPUT SIGNALS
|RECORD=17|IndexInSheet=104|OwnerPartId=-1|ShowNetName=T|Location.X=204|Location.Y=972|Orientation=2|Color=255|FontID=1|Text=ANT1_IO_OUT|IsCrossSheetConnector=T
|RECORD=41|OwnerIndex=1488|OwnerPartId=-1|Location.X=128|Location.X_Frac=3528|Location.Y=972|Orientation=2|Justification=3|Color=8388608|FontID=1|Text=FPGA[2C]|Name=CrossRef|ReadOnlyState=3
|RECORD=17|IndexInSheet=105|OwnerPartId=-1|ShowNetName=T|Location.X=204|Location.Y=917|Orientation=2|Color=255|FontID=1|Text=ANT1_IO_IN|IsCrossSheetConnector=T
|RECORD=41|OwnerIndex=1490|OwnerPartId=-1|Location.X=136|Location.X_Frac=96826|Location.Y=917|Orientation=2|Justification=3|Color=8388608|FontID=1|Text=FPGA[2C]|Name=CrossRef|ReadOnlyState=3
|RECORD=17|IndexInSheet=106|OwnerPartId=-1|ShowNetName=T|Location.X=204|Location.Y=642|Orientation=2|Color=255|FontID=1|Text=ANT2_IO_OUT|IsCrossSheetConnector=T
|RECORD=41|OwnerIndex=1492|OwnerPartId=-1|Location.X=128|Location.X_Frac=3528|Location.Y=642|Orientation=2|Justification=3|Color=8388608|FontID=1|Text=FPGA[2C]|Name=CrossRef|ReadOnlyState=3
|RECORD=17|IndexInSheet=107|OwnerPartId=-1|ShowNetName=T|Location.X=204|Location.Y=587|Orientation=2|Color=255|FontID=1|Text=ANT2_IO_IN|IsCrossSheetConnector=T
|RECORD=41|OwnerIndex=1494|OwnerPartId=-1|Location.X=136|Location.X_Frac=96826|Location.Y=587|Orientation=2|Justification=3|Color=8388608|FontID=1|Text=FPGA[2C]|Name=CrossRef|ReadOnlyState=3
|RECORD=17|IndexInSheet=108|OwnerPartId=-1|ShowNetName=T|Location.X=964|Location.Y=972|Orientation=2|Color=255|FontID=1|Text=ANT3_IO_OUT|IsCrossSheetConnector=T
|RECORD=41|OwnerIndex=1496|OwnerPartId=-1|Location.X=888|Location.X_Frac=3528|Location.Y=972|Orientation=2|Justification=3|Color=8388608|FontID=1|Text=FPGA[2C]|Name=CrossRef|ReadOnlyState=3
|RECORD=17|IndexInSheet=109|OwnerPartId=-1|ShowNetName=T|Location.X=964|Location.Y=917|Orientation=2|Color=255|FontID=1|Text=ANT3_IO_IN|IsCrossSheetConnector=T
|RECORD=41|OwnerIndex=1498|OwnerPartId=-1|Location.X=896|Location.X_Frac=96826|Location.Y=917|Orientation=2|Justification=3|Color=8388608|FontID=1|Text=FPGA[2C]|Name=CrossRef|ReadOnlyState=3
|RECORD=17|IndexInSheet=110|OwnerPartId=-1|ShowNetName=T|Location.X=964|Location.Y=642|Orientation=2|Color=255|FontID=1|Text=ANT4_IO_OUT|IsCrossSheetConnector=T
|RECORD=41|OwnerIndex=1500|OwnerPartId=-1|Location.X=888|Location.X_Frac=3528|Location.Y=642|Orientation=2|Justification=3|Color=8388608|FontID=1|Text=FPGA[2C]|Name=CrossRef|ReadOnlyState=3
|RECORD=17|IndexInSheet=111|OwnerPartId=-1|ShowNetName=T|Location.X=964|Location.Y=587|Orientation=2|Color=255|FontID=1|Text=ANT4_IO_IN|IsCrossSheetConnector=T
|RECORD=41|OwnerIndex=1502|OwnerPartId=-1|Location.X=896|Location.X_Frac=96826|Location.Y=587|Orientation=2|Justification=3|Color=8388608|FontID=1|Text=FPGA[2D]|Name=CrossRef|ReadOnlyState=3
|RECORD=27|IndexInSheet=112|OwnerPartId=-1|LineWidth=1|Color=8388608|LocationCount=2|X1=664|Y1=837|X2=664|Y2=822
|RECORD=27|IndexInSheet=113|OwnerPartId=-1|LineWidth=1|Color=8388608|LocationCount=2|X1=654|Y1=837|X2=654|Y2=822
|RECORD=27|IndexInSheet=114|OwnerPartId=-1|LineWidth=1|Color=8388608|LocationCount=3|X1=674|Y1=822|X2=704|Y2=822|X3=704|Y3=817
|RECORD=27|IndexInSheet=115|OwnerPartId=-1|LineWidth=1|Color=8388608|LocationCount=2|X1=624|Y1=867|X2=594|Y2=867
|RECORD=27|IndexInSheet=116|OwnerPartId=-1|LineWidth=1|Color=8388608|LocationCount=2|X1=274|Y1=997|X2=274|Y2=972
|RECORD=27|IndexInSheet=117|OwnerPartId=-1|LineWidth=1|Color=8388608|LocationCount=2|X1=304|Y1=997|X2=304|Y2=917
|RECORD=27|IndexInSheet=118|OwnerPartId=-1|LineWidth=1|Color=8388608|LocationCount=4|X1=644|Y1=917|X2=664|Y2=917|X3=704|Y3=917|X4=704|Y4=907
|RECORD=27|IndexInSheet=119|OwnerPartId=-1|LineWidth=1|Color=8388608|LocationCount=2|X1=594|Y1=947|X2=594|Y2=867
|RECORD=27|IndexInSheet=120|OwnerPartId=-1|LineWidth=1|Color=8388608|LocationCount=3|X1=504|Y1=892|X2=514|Y2=892|X3=514|Y3=947
|RECORD=27|IndexInSheet=121|OwnerPartId=-1|LineWidth=1|Color=8388608|LocationCount=3|X1=394|Y1=872|X2=334|Y2=872|X3=334|Y3=857
|RECORD=27|IndexInSheet=122|OwnerPartId=-1|LineWidth=1|Color=8388608|LocationCount=3|X1=394|Y1=862|X2=384|Y2=862|X3=384|Y3=817
|RECORD=27|IndexInSheet=123|OwnerPartId=-1|LineWidth=1|Color=8388608|LocationCount=2|X1=334|Y1=817|X2=334|Y2=827
|RECORD=27|IndexInSheet=124|OwnerPartId=-1|LineWidth=1|Color=8388608|LocationCount=2|X1=334|Y1=872|X2=334|Y2=1037
|RECORD=27|IndexInSheet=125|OwnerPartId=-1|LineWidth=1|Color=8388608|LocationCount=2|X1=1424|Y1=837|X2=1424|Y2=822
|RECORD=27|IndexInSheet=126|OwnerPartId=-1|LineWidth=1|Color=8388608|LocationCount=2|X1=1414|Y1=837|X2=1414|Y2=822
|RECORD=27|IndexInSheet=127|OwnerPartId=-1|LineWidth=1|Color=8388608|LocationCount=3|X1=1434|Y1=822|X2=1464|Y2=822|X3=1464|Y3=817
|RECORD=27|IndexInSheet=128|OwnerPartId=-1|LineWidth=1|Color=8388608|LocationCount=2|X1=1384|Y1=867|X2=1354|Y2=867
|RECORD=27|IndexInSheet=129|OwnerPartId=-1|LineWidth=1|Color=8388608|LocationCount=2|X1=1034|Y1=997|X2=1034|Y2=972
|RECORD=27|IndexInSheet=130|OwnerPartId=-1|LineWidth=1|Color=8388608|LocationCount=2|X1=1064|Y1=997|X2=1064|Y2=917
|RECORD=27|IndexInSheet=131|OwnerPartId=-1|LineWidth=1|Color=8388608|LocationCount=4|X1=1404|Y1=917|X2=1424|Y2=917|X3=1464|Y3=917|X4=1464|Y4=907
|RECORD=27|IndexInSheet=132|OwnerPartId=-1|LineWidth=1|Color=8388608|LocationCount=2|X1=1354|Y1=947|X2=1354|Y2=867
|RECORD=27|IndexInSheet=133|OwnerPartId=-1|LineWidth=1|Color=8388608|LocationCount=3|X1=1264|Y1=892|X2=1274|Y2=892|X3=1274|Y3=947
|RECORD=27|IndexInSheet=134|OwnerPartId=-1|LineWidth=1|Color=8388608|LocationCount=3|X1=1154|Y1=872|X2=1094|Y2=872|X3=1094|Y3=857
|RECORD=27|IndexInSheet=135|OwnerPartId=-1|LineWidth=1|Color=8388608|LocationCount=3|X1=1154|Y1=862|X2=1144|Y2=862|X3=1144|Y3=817
|RECORD=27|IndexInSheet=136|OwnerPartId=-1|LineWidth=1|Color=8388608|LocationCount=2|X1=1094|Y1=817|X2=1094|Y2=827
|RECORD=27|IndexInSheet=137|OwnerPartId=-1|LineWidth=1|Color=8388608|LocationCount=2|X1=1094|Y1=872|X2=1094|Y2=1037
|RECORD=27|IndexInSheet=138|OwnerPartId=-1|LineWidth=1|Color=8388608|LocationCount=2|X1=1424|Y1=507|X2=1424|Y2=492
|RECORD=27|IndexInSheet=139|OwnerPartId=-1|LineWidth=1|Color=8388608|LocationCount=2|X1=1414|Y1=507|X2=1414|Y2=492
|RECORD=27|IndexInSheet=140|OwnerPartId=-1|LineWidth=1|Color=8388608|LocationCount=3|X1=1434|Y1=492|X2=1464|Y2=492|X3=1464|Y3=487
|RECORD=27|IndexInSheet=141|OwnerPartId=-1|LineWidth=1|Color=8388608|LocationCount=2|X1=1034|Y1=667|X2=1034|Y2=642
|RECORD=27|IndexInSheet=142|OwnerPartId=-1|LineWidth=1|Color=8388608|LocationCount=2|X1=1064|Y1=667|X2=1064|Y2=587
|RECORD=27|IndexInSheet=143|OwnerPartId=-1|LineWidth=1|Color=8388608|LocationCount=4|X1=1404|Y1=587|X2=1424|Y2=587|X3=1464|Y3=587|X4=1464|Y4=577
|RECORD=27|IndexInSheet=144|OwnerPartId=-1|LineWidth=1|Color=8388608|LocationCount=3|X1=1264|Y1=562|X2=1274|Y2=562|X3=1274|Y3=617
|RECORD=27|IndexInSheet=145|OwnerPartId=-1|LineWidth=1|Color=8388608|LocationCount=3|X1=1154|Y1=542|X2=1094|Y2=542|X3=1094|Y3=527
|RECORD=27|IndexInSheet=146|OwnerPartId=-1|LineWidth=1|Color=8388608|LocationCount=3|X1=1154|Y1=532|X2=1144|Y2=532|X3=1144|Y3=487
|RECORD=27|IndexInSheet=147|OwnerPartId=-1|LineWidth=1|Color=8388608|LocationCount=2|X1=1094|Y1=487|X2=1094|Y2=497
|RECORD=27|IndexInSheet=148|OwnerPartId=-1|LineWidth=1|Color=8388608|LocationCount=2|X1=1094|Y1=542|X2=1094|Y2=707
|RECORD=27|IndexInSheet=149|OwnerPartId=-1|LineWidth=1|Color=8388608|LocationCount=2|X1=664|Y1=507|X2=664|Y2=492
|RECORD=27|IndexInSheet=150|OwnerPartId=-1|LineWidth=1|Color=8388608|LocationCount=2|X1=654|Y1=507|X2=654|Y2=492
|RECORD=27|IndexInSheet=151|OwnerPartId=-1|LineWidth=1|Color=8388608|LocationCount=3|X1=674|Y1=492|X2=704|Y2=492|X3=704|Y3=487
|RECORD=27|IndexInSheet=152|OwnerPartId=-1|LineWidth=1|Color=8388608|LocationCount=2|X1=274|Y1=667|X2=274|Y2=642
|RECORD=27|IndexInSheet=153|OwnerPartId=-1|LineWidth=1|Color=8388608|LocationCount=2|X1=304|Y1=667|X2=304|Y2=587
|RECORD=27|IndexInSheet=154|OwnerPartId=-1|LineWidth=1|Color=8388608|LocationCount=4|X1=644|Y1=587|X2=664|Y2=587|X3=704|Y3=587|X4=704|Y4=577
|RECORD=27|IndexInSheet=155|OwnerPartId=-1|LineWidth=1|Color=8388608|LocationCount=3|X1=504|Y1=562|X2=514|Y2=562|X3=514|Y3=617
|RECORD=27|IndexInSheet=156|OwnerPartId=-1|LineWidth=1|Color=8388608|LocationCount=3|X1=394|Y1=542|X2=334|Y2=542|X3=334|Y3=527
|RECORD=27|IndexInSheet=157|OwnerPartId=-1|LineWidth=1|Color=8388608|LocationCount=3|X1=394|Y1=532|X2=384|Y2=532|X3=384|Y3=487
|RECORD=27|IndexInSheet=158|OwnerPartId=-1|LineWidth=1|Color=8388608|LocationCount=2|X1=334|Y1=487|X2=334|Y2=497
|RECORD=27|IndexInSheet=159|OwnerPartId=-1|LineWidth=1|Color=8388608|LocationCount=2|X1=334|Y1=542|X2=334|Y2=707
|RECORD=27|IndexInSheet=160|OwnerPartId=-1|LineWidth=1|Color=8388608|LocationCount=2|X1=594|Y1=777|X2=594|Y2=867
|RECORD=27|IndexInSheet=161|OwnerPartId=-1|LineWidth=1|Color=8388608|LocationCount=2|X1=594|Y1=727|X2=594|Y2=617
|RECORD=27|IndexInSheet=162|OwnerPartId=-1|LineWidth=1|Color=8388608|LocationCount=2|X1=1354|Y1=777|X2=1354|Y2=867
|RECORD=27|IndexInSheet=163|OwnerPartId=-1|LineWidth=1|Color=8388608|LocationCount=2|X1=1354|Y1=727|X2=1354|Y2=617
|RECORD=27|IndexInSheet=164|OwnerPartId=-1|LineWidth=1|Color=8388608|LocationCount=2|X1=574|Y1=777|X2=574|Y2=797
|RECORD=27|IndexInSheet=165|OwnerPartId=-1|LineWidth=1|Color=8388608|LocationCount=2|X1=574|Y1=707|X2=574|Y2=727
|RECORD=27|IndexInSheet=166|OwnerPartId=-1|LineWidth=1|Color=8388608|LocationCount=2|X1=1334|Y1=777|X2=1334|Y2=797
|RECORD=27|IndexInSheet=167|OwnerPartId=-1|LineWidth=1|Color=8388608|LocationCount=2|X1=1334|Y1=707|X2=1334|Y2=727
|RECORD=27|IndexInSheet=168|OwnerPartId=-1|LineWidth=1|Color=8388608|LocationCount=2|X1=394|Y1=562|X2=264|Y2=562
|RECORD=27|IndexInSheet=169|OwnerPartId=-1|LineWidth=1|Color=8388608|LocationCount=2|X1=264|Y1=617|X2=394|Y2=617
|RECORD=27|IndexInSheet=170|OwnerPartId=-1|LineWidth=1|Color=8388608|LocationCount=2|X1=394|Y1=892|X2=264|Y2=892
|RECORD=27|IndexInSheet=171|OwnerPartId=-1|LineWidth=1|Color=8388608|LocationCount=2|X1=264|Y1=947|X2=394|Y2=947
|RECORD=27|IndexInSheet=172|OwnerPartId=-1|LineWidth=1|Color=8388608|LocationCount=3|X1=624|Y1=537|X2=594|Y2=537|X3=594|Y3=617
|RECORD=27|IndexInSheet=173|OwnerPartId=-1|LineWidth=1|Color=8388608|LocationCount=2|X1=1154|Y1=562|X2=1024|Y2=562
|RECORD=27|IndexInSheet=174|OwnerPartId=-1|LineWidth=1|Color=8388608|LocationCount=2|X1=1024|Y1=617|X2=1154|Y2=617
|RECORD=27|IndexInSheet=175|OwnerPartId=-1|LineWidth=1|Color=8388608|LocationCount=2|X1=1154|Y1=892|X2=1024|Y2=892
|RECORD=27|IndexInSheet=176|OwnerPartId=-1|LineWidth=1|Color=8388608|LocationCount=2|X1=1024|Y1=947|X2=1154|Y2=947
|RECORD=27|IndexInSheet=177|OwnerPartId=-1|LineWidth=1|Color=8388608|LocationCount=3|X1=1384|Y1=537|X2=1354|Y2=537|X3=1354|Y3=617
|RECORD=27|IndexInSheet=178|OwnerPartId=-1|LineWidth=1|Color=8388608|LocationCount=3|X1=394|Y1=587|X2=304|Y2=587|X3=204|Y3=587
|RECORD=27|IndexInSheet=179|OwnerPartId=-1|LineWidth=1|Color=8388608|LocationCount=3|X1=394|Y1=642|X2=274|Y2=642|X3=204|Y3=642
|RECORD=27|IndexInSheet=180|OwnerPartId=-1|LineWidth=1|Color=8388608|LocationCount=3|X1=394|Y1=917|X2=304|Y2=917|X3=204|Y3=917
|RECORD=27|IndexInSheet=181|OwnerPartId=-1|LineWidth=1|Color=8388608|LocationCount=3|X1=394|Y1=972|X2=274|Y2=972|X3=204|Y3=972
|RECORD=27|IndexInSheet=182|OwnerPartId=-1|LineWidth=1|Color=8388608|LocationCount=3|X1=504|Y1=617|X2=514|Y2=617|X3=529|Y3=617
|RECORD=27|IndexInSheet=183|OwnerPartId=-1|LineWidth=1|Color=8388608|LocationCount=3|X1=504|Y1=947|X2=514|Y2=947|X3=529|Y3=947
|RECORD=27|IndexInSheet=184|OwnerPartId=-1|LineWidth=1|Color=8388608|LocationCount=4|X1=624|Y1=617|X2=594|Y2=617|X3=569|Y3=617|X4=549|Y4=617
|RECORD=27|IndexInSheet=185|OwnerPartId=-1|LineWidth=1|Color=8388608|LocationCount=4|X1=624|Y1=947|X2=594|Y2=947|X3=569|Y3=947|X4=549|Y4=947
|RECORD=27|IndexInSheet=186|OwnerPartId=-1|LineWidth=1|Color=8388608|LocationCount=3|X1=1154|Y1=587|X2=1064|Y2=587|X3=964|Y3=587
|RECORD=27|IndexInSheet=187|OwnerPartId=-1|LineWidth=1|Color=8388608|LocationCount=3|X1=1154|Y1=642|X2=1034|Y2=642|X3=964|Y3=642
|RECORD=27|IndexInSheet=188|OwnerPartId=-1|LineWidth=1|Color=8388608|LocationCount=3|X1=1154|Y1=917|X2=1064|Y2=917|X3=964|Y3=917
|RECORD=27|IndexInSheet=189|OwnerPartId=-1|LineWidth=1|Color=8388608|LocationCount=3|X1=1154|Y1=972|X2=1034|Y2=972|X3=964|Y3=972
|RECORD=27|IndexInSheet=190|OwnerPartId=-1|LineWidth=1|Color=8388608|LocationCount=3|X1=1264|Y1=617|X2=1274|Y2=617|X3=1289|Y3=617
|RECORD=27|IndexInSheet=191|OwnerPartId=-1|LineWidth=1|Color=8388608|LocationCount=3|X1=1264|Y1=947|X2=1274|Y2=947|X3=1289|Y3=947
|RECORD=27|IndexInSheet=192|OwnerPartId=-1|LineWidth=1|Color=8388608|LocationCount=4|X1=1384|Y1=947|X2=1354|Y2=947|X3=1329|Y3=947|X4=1309|Y4=947
|RECORD=27|IndexInSheet=193|OwnerPartId=-1|LineWidth=1|Color=8388608|LocationCount=3|X1=1384|Y1=617|X2=1354|Y2=617|X3=1329|Y3=617
|RECORD=27|IndexInSheet=194|OwnerPartId=-1|LineWidth=1|Color=8388608|LocationCount=6|X1=674|Y1=507|X2=674|Y2=492|X3=664|Y3=492|X4=654|Y4=492|X5=644|Y5=492|X6=644|Y6=507
|RECORD=27|IndexInSheet=195|OwnerPartId=-1|LineWidth=1|Color=8388608|LocationCount=6|X1=674|Y1=837|X2=674|Y2=822|X3=664|Y3=822|X4=654|Y4=822|X5=644|Y5=822|X6=644|Y6=837
|RECORD=27|IndexInSheet=196|OwnerPartId=-1|LineWidth=1|Color=8388608|LocationCount=6|X1=1434|Y1=507|X2=1434|Y2=492|X3=1424|Y3=492|X4=1414|Y4=492|X5=1404|Y5=492|X6=1404|Y6=507
|RECORD=27|IndexInSheet=197|OwnerPartId=-1|LineWidth=1|Color=8388608|LocationCount=6|X1=1434|Y1=837|X2=1434|Y2=822|X3=1424|Y3=822|X4=1414|Y4=822|X5=1404|Y5=822|X6=1404|Y6=837
|RECORD=17|IndexInSheet=198|OwnerPartId=-1|Style=4|ShowNetName=T|Location.X=1464|Location.Y=487|Orientation=3|Color=128|FontID=1|Text=GND
|RECORD=29|IndexInSheet=-1|OwnerPartId=-1|Location.X=274|Location.Y=642|Color=128
|RECORD=29|IndexInSheet=-1|OwnerPartId=-1|Location.X=274|Location.Y=972|Color=128
|RECORD=29|IndexInSheet=-1|OwnerPartId=-1|Location.X=304|Location.Y=587|Color=128
|RECORD=29|IndexInSheet=-1|OwnerPartId=-1|Location.X=304|Location.Y=917|Color=128
|RECORD=29|IndexInSheet=-1|OwnerPartId=-1|Location.X=334|Location.Y=542|Color=128
|RECORD=29|IndexInSheet=-1|OwnerPartId=-1|Location.X=334|Location.Y=872|Color=128
|RECORD=29|IndexInSheet=-1|OwnerPartId=-1|Location.X=514|Location.Y=617|Color=128
|RECORD=29|IndexInSheet=-1|OwnerPartId=-1|Location.X=514|Location.Y=947|Color=128
|RECORD=29|IndexInSheet=-1|OwnerPartId=-1|Location.X=569|Location.Y=617|Color=128
|RECORD=29|IndexInSheet=-1|OwnerPartId=-1|Location.X=569|Location.Y=947|Color=128
|RECORD=29|IndexInSheet=-1|OwnerPartId=-1|Location.X=594|Location.Y=617|Color=128
|RECORD=29|IndexInSheet=-1|OwnerPartId=-1|Location.X=594|Location.Y=867|Color=128
|RECORD=29|IndexInSheet=-1|OwnerPartId=-1|Location.X=594|Location.Y=947|Color=128
|RECORD=29|IndexInSheet=-1|OwnerPartId=-1|Location.X=654|Location.Y=492|Color=128
|RECORD=29|IndexInSheet=-1|OwnerPartId=-1|Location.X=654|Location.Y=822|Color=128
|RECORD=29|IndexInSheet=-1|OwnerPartId=-1|Location.X=664|Location.Y=492|Color=128
|RECORD=29|IndexInSheet=-1|OwnerPartId=-1|Location.X=664|Location.Y=587|Color=128
|RECORD=29|IndexInSheet=-1|OwnerPartId=-1|Location.X=664|Location.Y=822|Color=128
|RECORD=29|IndexInSheet=-1|OwnerPartId=-1|Location.X=664|Location.Y=917|Color=128
|RECORD=29|IndexInSheet=-1|OwnerPartId=-1|Location.X=674|Location.Y=492|Color=128
|RECORD=29|IndexInSheet=-1|OwnerPartId=-1|Location.X=674|Location.Y=822|Color=128
|RECORD=29|IndexInSheet=-1|OwnerPartId=-1|Location.X=1034|Location.Y=642|Color=128
|RECORD=29|IndexInSheet=-1|OwnerPartId=-1|Location.X=1034|Location.Y=972|Color=128
|RECORD=29|IndexInSheet=-1|OwnerPartId=-1|Location.X=1064|Location.Y=587|Color=128
|RECORD=29|IndexInSheet=-1|OwnerPartId=-1|Location.X=1064|Location.Y=917|Color=128
|RECORD=29|IndexInSheet=-1|OwnerPartId=-1|Location.X=1094|Location.Y=542|Color=128
|RECORD=29|IndexInSheet=-1|OwnerPartId=-1|Location.X=1094|Location.Y=872|Color=128
|RECORD=29|IndexInSheet=-1|OwnerPartId=-1|Location.X=1274|Location.Y=617|Color=128
|RECORD=29|IndexInSheet=-1|OwnerPartId=-1|Location.X=1274|Location.Y=947|Color=128
|RECORD=29|IndexInSheet=-1|OwnerPartId=-1|Location.X=1329|Location.Y=947|Color=128
|RECORD=29|IndexInSheet=-1|OwnerPartId=-1|Location.X=1354|Location.Y=617|Color=128
|RECORD=29|IndexInSheet=-1|OwnerPartId=-1|Location.X=1354|Location.Y=867|Color=128
|RECORD=29|IndexInSheet=-1|OwnerPartId=-1|Location.X=1354|Location.Y=947|Color=128
|RECORD=29|IndexInSheet=-1|OwnerPartId=-1|Location.X=1414|Location.Y=492|Color=128
|RECORD=29|IndexInSheet=-1|OwnerPartId=-1|Location.X=1414|Location.Y=822|Color=128
|RECORD=29|IndexInSheet=-1|OwnerPartId=-1|Location.X=1424|Location.Y=492|Color=128
|RECORD=29|IndexInSheet=-1|OwnerPartId=-1|Location.X=1424|Location.Y=587|Color=128
|RECORD=29|IndexInSheet=-1|OwnerPartId=-1|Location.X=1424|Location.Y=822|Color=128
|RECORD=29|IndexInSheet=-1|OwnerPartId=-1|Location.X=1424|Location.Y=917|Color=128
|RECORD=29|IndexInSheet=-1|OwnerPartId=-1|Location.X=1434|Location.Y=492|Color=128
|RECORD=29|IndexInSheet=-1|OwnerPartId=-1|Location.X=1434|Location.Y=822|Color=128